(kicad_sch
	(version 20250114)
	(generator "eeschema")
	(generator_version "9.0")
	(paper "A3")
	(title_block
		(title "GMSL Deserializer")
		(date "2025-10-09")
		(rev "1.0.4")
		(company "Antmicro Ltd")
		(comment 1 "www.antmicro.com")
	)
	(text "Multi-function pins"
		(exclude_from_sim no)
		(at 21.59 177.165 0)
		(effects
			(font
				(size 4 4)
				(thickness 0.8)
				(bold yes)
			)
			(justify left bottom)
		)
	)
	(text "CSI connector"
		(exclude_from_sim no)
		(at 304.165 63.5 0)
		(effects
			(font
				(size 4 4)
				(thickness 0.8)
				(bold yes)
			)
			(justify left bottom)
		)
	)
	(text "Fakra connectors"
		(exclude_from_sim no)
		(at 133.985 172.72 0)
		(effects
			(font
				(size 4 4)
				(thickness 0.8)
				(bold yes)
			)
			(justify left bottom)
		)
	)
	(text "Buffer gates"
		(exclude_from_sim no)
		(at 143.51 40.64 0)
		(effects
			(font
				(size 4 4)
				(thickness 0.8)
				(bold yes)
			)
			(justify left bottom)
		)
	)
	(text "Power connector"
		(exclude_from_sim no)
		(at 26.035 54.61 0)
		(effects
			(font
				(size 4 4)
				(thickness 0.8)
				(bold yes)
			)
			(justify left bottom)
		)
	)
	(text "Level shifter"
		(exclude_from_sim no)
		(at 137.795 101.6 0)
		(effects
			(font
				(size 4 4)
				(thickness 0.8)
				(bold yes)
			)
			(justify left bottom)
		)
	)
	(junction
		(at 97.79 132.08)
		(diameter 0)
		(color 0 0 0 0)
	)
	(junction
		(at 289.56 157.48)
		(diameter 0)
		(color 0 0 0 0)
	)
	(junction
		(at 303.53 175.26)
		(diameter 0)
		(color 0 0 0 0)
	)
	(junction
		(at 349.25 114.3)
		(diameter 0)
		(color 0 0 0 0)
	)
	(junction
		(at 151.13 233.68)
		(diameter 0)
		(color 0 0 0 0)
	)
	(junction
		(at 34.29 69.85)
		(diameter 0)
		(color 0 0 0 0)
	)
	(junction
		(at 349.25 208.28)
		(diameter 0)
		(color 0 0 0 0)
	)
	(junction
		(at 132.08 113.03)
		(diameter 0)
		(color 0 0 0 0)
	)
	(junction
		(at 308.61 177.8)
		(diameter 0)
		(color 0 0 0 0)
	)
	(junction
		(at 342.9 200.66)
		(diameter 0)
		(color 0 0 0 0)
	)
	(junction
		(at 351.79 195.58)
		(diameter 0)
		(color 0 0 0 0)
	)
	(junction
		(at 323.85 200.66)
		(diameter 0)
		(color 0 0 0 0)
	)
	(junction
		(at 135.89 134.62)
		(diameter 0)
		(color 0 0 0 0)
	)
	(junction
		(at 184.15 134.62)
		(diameter 0)
		(color 0 0 0 0)
	)
	(junction
		(at 200.66 55.88)
		(diameter 0)
		(color 0 0 0 0)
	)
	(junction
		(at 120.65 124.46)
		(diameter 0)
		(color 0 0 0 0)
	)
	(junction
		(at 284.48 162.56)
		(diameter 0)
		(color 0 0 0 0)
	)
	(junction
		(at 195.58 72.39)
		(diameter 0)
		(color 0 0 0 0)
	)
	(junction
		(at 349.25 144.78)
		(diameter 0)
		(color 0 0 0 0)
	)
	(junction
		(at 349.25 121.92)
		(diameter 0)
		(color 0 0 0 0)
	)
	(junction
		(at 140.97 72.39)
		(diameter 0)
		(color 0 0 0 0)
	)
	(junction
		(at 279.4 157.48)
		(diameter 0)
		(color 0 0 0 0)
	)
	(junction
		(at 45.72 69.85)
		(diameter 0)
		(color 0 0 0 0)
	)
	(junction
		(at 337.82 200.66)
		(diameter 0)
		(color 0 0 0 0)
	)
	(junction
		(at 190.5 132.08)
		(diameter 0)
		(color 0 0 0 0)
	)
	(junction
		(at 175.26 114.3)
		(diameter 0)
		(color 0 0 0 0)
	)
	(junction
		(at 127 134.62)
		(diameter 0)
		(color 0 0 0 0)
	)
	(junction
		(at 27.94 246.38)
		(diameter 0)
		(color 0 0 0 0)
	)
	(junction
		(at 317.5 200.66)
		(diameter 0)
		(color 0 0 0 0)
	)
	(junction
		(at 289.56 162.56)
		(diameter 0)
		(color 0 0 0 0)
	)
	(junction
		(at 313.69 177.8)
		(diameter 0)
		(color 0 0 0 0)
	)
	(junction
		(at 349.25 106.68)
		(diameter 0)
		(color 0 0 0 0)
	)
	(junction
		(at 102.87 134.62)
		(diameter 0)
		(color 0 0 0 0)
	)
	(junction
		(at 151.13 210.82)
		(diameter 0)
		(color 0 0 0 0)
	)
	(junction
		(at 317.5 195.58)
		(diameter 0)
		(color 0 0 0 0)
	)
	(junction
		(at 151.13 257.81)
		(diameter 0)
		(color 0 0 0 0)
	)
	(junction
		(at 55.88 69.85)
		(diameter 0)
		(color 0 0 0 0)
	)
	(junction
		(at 349.25 205.74)
		(diameter 0)
		(color 0 0 0 0)
	)
	(junction
		(at 306.07 195.58)
		(diameter 0)
		(color 0 0 0 0)
	)
	(junction
		(at 146.05 55.88)
		(diameter 0)
		(color 0 0 0 0)
	)
	(junction
		(at 316.23 175.26)
		(diameter 0)
		(color 0 0 0 0)
	)
	(junction
		(at 49.53 69.85)
		(diameter 0)
		(color 0 0 0 0)
	)
	(junction
		(at 190.5 124.46)
		(diameter 0)
		(color 0 0 0 0)
	)
	(junction
		(at 27.94 74.93)
		(diameter 0)
		(color 0 0 0 0)
	)
	(junction
		(at 335.28 195.58)
		(diameter 0)
		(color 0 0 0 0)
	)
	(junction
		(at 120.65 132.08)
		(diameter 0)
		(color 0 0 0 0)
	)
	(junction
		(at 349.25 152.4)
		(diameter 0)
		(color 0 0 0 0)
	)
	(junction
		(at 351.79 200.66)
		(diameter 0)
		(color 0 0 0 0)
	)
	(junction
		(at 330.2 195.58)
		(diameter 0)
		(color 0 0 0 0)
	)
	(junction
		(at 311.15 200.66)
		(diameter 0)
		(color 0 0 0 0)
	)
	(junction
		(at 151.13 186.69)
		(diameter 0)
		(color 0 0 0 0)
	)
	(junction
		(at 140.97 113.03)
		(diameter 0)
		(color 0 0 0 0)
	)
	(junction
		(at 134.62 132.08)
		(diameter 0)
		(color 0 0 0 0)
	)
	(no_connect
		(at 351.79 165.1)
	)
	(no_connect
		(at 351.79 160.02)
	)
	(no_connect
		(at 351.79 111.76)
	)
	(no_connect
		(at 351.79 185.42)
	)
	(no_connect
		(at 351.79 172.72)
	)
	(no_connect
		(at 351.79 170.18)
	)
	(no_connect
		(at 351.79 109.22)
	)
	(no_connect
		(at 351.79 119.38)
	)
	(no_connect
		(at 351.79 154.94)
	)
	(no_connect
		(at 351.79 167.64)
	)
	(no_connect
		(at 351.79 190.5)
	)
	(no_connect
		(at 351.79 187.96)
	)
	(no_connect
		(at 351.79 193.04)
	)
	(no_connect
		(at 351.79 116.84)
	)
	(bus_entry
		(at 331.47 127)
		(size -1.27 1.27)
		(stroke
			(width 0)
			(type default)
		)
	)
	(bus_entry
		(at 331.47 132.08)
		(size -1.27 1.27)
		(stroke
			(width 0)
			(type default)
		)
	)
	(bus_entry
		(at 331.47 137.16)
		(size -1.27 1.27)
		(stroke
			(width 0)
			(type default)
		)
	)
	(bus_entry
		(at 331.47 86.36)
		(size -1.27 1.27)
		(stroke
			(width 0)
			(type default)
		)
	)
	(bus_entry
		(at 331.47 78.74)
		(size -1.27 1.27)
		(stroke
			(width 0)
			(type default)
		)
	)
	(bus_entry
		(at 48.26 190.5)
		(size -1.27 1.27)
		(stroke
			(width 0)
			(type default)
		)
	)
	(bus_entry
		(at 48.26 195.58)
		(size -1.27 1.27)
		(stroke
			(width 0)
			(type default)
		)
	)
	(bus_entry
		(at 331.47 147.32)
		(size -1.27 1.27)
		(stroke
			(width 0)
			(type default)
		)
	)
	(bus_entry
		(at 331.47 134.62)
		(size -1.27 1.27)
		(stroke
			(width 0)
			(type default)
		)
	)
	(bus_entry
		(at 331.47 91.44)
		(size -1.27 1.27)
		(stroke
			(width 0)
			(type default)
		)
	)
	(bus_entry
		(at 331.47 88.9)
		(size -1.27 1.27)
		(stroke
			(width 0)
			(type default)
		)
	)
	(bus_entry
		(at 331.47 96.52)
		(size -1.27 1.27)
		(stroke
			(width 0)
			(type default)
		)
	)
	(bus_entry
		(at 48.26 187.96)
		(size -1.27 1.27)
		(stroke
			(width 0)
			(type default)
		)
	)
	(bus_entry
		(at 331.47 129.54)
		(size -1.27 1.27)
		(stroke
			(width 0)
			(type default)
		)
	)
	(bus_entry
		(at 331.47 101.6)
		(size -1.27 1.27)
		(stroke
			(width 0)
			(type default)
		)
	)
	(bus_entry
		(at 331.47 142.24)
		(size -1.27 1.27)
		(stroke
			(width 0)
			(type default)
		)
	)
	(bus_entry
		(at 331.47 93.98)
		(size -1.27 1.27)
		(stroke
			(width 0)
			(type default)
		)
	)
	(bus_entry
		(at 331.47 149.86)
		(size -1.27 1.27)
		(stroke
			(width 0)
			(type default)
		)
	)
	(bus_entry
		(at 331.47 139.7)
		(size -1.27 1.27)
		(stroke
			(width 0)
			(type default)
		)
	)
	(bus_entry
		(at 331.47 124.46)
		(size -1.27 1.27)
		(stroke
			(width 0)
			(type default)
		)
	)
	(bus_entry
		(at 331.47 104.14)
		(size -1.27 1.27)
		(stroke
			(width 0)
			(type default)
		)
	)
	(bus_entry
		(at 331.47 83.82)
		(size -1.27 1.27)
		(stroke
			(width 0)
			(type default)
		)
	)
	(bus_entry
		(at 48.26 198.12)
		(size -1.27 1.27)
		(stroke
			(width 0)
			(type default)
		)
	)
	(bus_entry
		(at 48.26 200.66)
		(size -1.27 1.27)
		(stroke
			(width 0)
			(type default)
		)
	)
	(bus_entry
		(at 48.26 203.2)
		(size -1.27 1.27)
		(stroke
			(width 0)
			(type default)
		)
	)
	(bus_entry
		(at 48.26 205.74)
		(size -1.27 1.27)
		(stroke
			(width 0)
			(type default)
		)
	)
	(bus_entry
		(at 48.26 193.04)
		(size -1.27 1.27)
		(stroke
			(width 0)
			(type default)
		)
	)
	(bus_entry
		(at 331.47 81.28)
		(size -1.27 1.27)
		(stroke
			(width 0)
			(type default)
		)
	)
	(wire
		(pts
			(xy 198.12 76.2) (xy 195.58 76.2)
		)
		(stroke
			(width 0)
			(type default)
		)
	)
	(wire
		(pts
			(xy 306.07 208.28) (xy 306.07 207.01)
		)
		(stroke
			(width 0)
			(type default)
		)
	)
	(wire
		(pts
			(xy 331.47 127) (xy 351.79 127)
		)
		(stroke
			(width 0)
			(type default)
		)
	)
	(wire
		(pts
			(xy 349.25 205.74) (xy 351.79 205.74)
		)
		(stroke
			(width 0)
			(type default)
		)
	)
	(wire
		(pts
			(xy 166.37 114.3) (xy 166.37 129.54)
		)
		(stroke
			(width 0)
			(type default)
		)
	)
	(wire
		(pts
			(xy 349.25 121.92) (xy 349.25 144.78)
		)
		(stroke
			(width 0)
			(type default)
		)
	)
	(wire
		(pts
			(xy 303.53 162.56) (xy 351.79 162.56)
		)
		(stroke
			(width 0)
			(type default)
		)
	)
	(bus
		(pts
			(xy 46.99 189.23) (xy 46.99 191.77)
		)
		(stroke
			(width 0)
			(type default)
		)
	)
	(wire
		(pts
			(xy 193.04 76.2) (xy 191.77 76.2)
		)
		(stroke
			(width 0)
			(type default)
		)
	)
	(wire
		(pts
			(xy 195.58 68.58) (xy 195.58 55.88)
		)
		(stroke
			(width 0)
			(type default)
		)
	)
	(wire
		(pts
			(xy 48.26 190.5) (xy 53.34 190.5)
		)
		(stroke
			(width 0)
			(type default)
		)
	)
	(wire
		(pts
			(xy 113.03 132.08) (xy 120.65 132.08)
		)
		(stroke
			(width 0)
			(type default)
		)
	)
	(wire
		(pts
			(xy 190.5 124.46) (xy 190.5 125.73)
		)
		(stroke
			(width 0)
			(type default)
		)
	)
	(wire
		(pts
			(xy 284.48 162.56) (xy 284.48 165.1)
		)
		(stroke
			(width 0)
			(type default)
		)
	)
	(wire
		(pts
			(xy 292.1 175.26) (xy 303.53 175.26)
		)
		(stroke
			(width 0)
			(type default)
		)
	)
	(wire
		(pts
			(xy 127 130.81) (xy 127 134.62)
		)
		(stroke
			(width 0)
			(type default)
		)
	)
	(wire
		(pts
			(xy 137.16 123.19) (xy 137.16 125.73)
		)
		(stroke
			(width 0)
			(type default)
		)
	)
	(wire
		(pts
			(xy 191.77 68.58) (xy 195.58 68.58)
		)
		(stroke
			(width 0)
			(type default)
		)
	)
	(wire
		(pts
			(xy 119.38 139.7) (xy 134.62 139.7)
		)
		(stroke
			(width 0)
			(type default)
		)
	)
	(wire
		(pts
			(xy 114.3 139.7) (xy 101.6 139.7)
		)
		(stroke
			(width 0)
			(type default)
		)
	)
	(wire
		(pts
			(xy 303.53 185.42) (xy 303.53 186.69)
		)
		(stroke
			(width 0)
			(type default)
		)
	)
	(wire
		(pts
			(xy 144.78 137.16) (xy 137.16 137.16)
		)
		(stroke
			(width 0)
			(type default)
		)
	)
	(wire
		(pts
			(xy 289.56 162.56) (xy 298.45 162.56)
		)
		(stroke
			(width 0)
			(type default)
		)
	)
	(wire
		(pts
			(xy 78.74 91.44) (xy 66.04 91.44)
		)
		(stroke
			(width 0)
			(type default)
		)
	)
	(wire
		(pts
			(xy 143.51 76.2) (xy 140.97 76.2)
		)
		(stroke
			(width 0)
			(type default)
		)
	)
	(wire
		(pts
			(xy 147.32 186.69) (xy 151.13 186.69)
		)
		(stroke
			(width 0)
			(type default)
		)
	)
	(wire
		(pts
			(xy 308.61 177.8) (xy 313.69 177.8)
		)
		(stroke
			(width 0)
			(type default)
		)
	)
	(wire
		(pts
			(xy 45.72 69.85) (xy 45.72 71.12)
		)
		(stroke
			(width 0)
			(type default)
		)
	)
	(polyline
		(pts
			(xy 90.17 12.065) (xy 90.17 285.115)
		)
		(stroke
			(width 0)
			(type dash)
		)
	)
	(wire
		(pts
			(xy 120.65 73.66) (xy 120.65 68.58)
		)
		(stroke
			(width 0)
			(type default)
		)
	)
	(wire
		(pts
			(xy 331.47 96.52) (xy 351.79 96.52)
		)
		(stroke
			(width 0)
			(type default)
		)
	)
	(bus
		(pts
			(xy 45.72 209.55) (xy 39.37 209.55)
		)
		(stroke
			(width 0)
			(type default)
		)
	)
	(wire
		(pts
			(xy 261.62 162.56) (xy 284.48 162.56)
		)
		(stroke
			(width 0)
			(type default)
		)
	)
	(wire
		(pts
			(xy 138.43 76.2) (xy 137.16 76.2)
		)
		(stroke
			(width 0)
			(type default)
		)
	)
	(bus
		(pts
			(xy 330.2 85.09) (xy 330.2 87.63)
		)
		(stroke
			(width 0)
			(type default)
		)
	)
	(bus
		(pts
			(xy 330.2 152.4) (xy 328.93 153.67)
		)
		(stroke
			(width 0)
			(type default)
		)
	)
	(wire
		(pts
			(xy 48.26 187.96) (xy 53.34 187.96)
		)
		(stroke
			(width 0)
			(type default)
		)
	)
	(wire
		(pts
			(xy 317.5 200.66) (xy 323.85 200.66)
		)
		(stroke
			(width 0)
			(type default)
		)
	)
	(wire
		(pts
			(xy 48.26 203.2) (xy 53.34 203.2)
		)
		(stroke
			(width 0)
			(type default)
		)
	)
	(wire
		(pts
			(xy 134.62 132.08) (xy 144.78 132.08)
		)
		(stroke
			(width 0)
			(type default)
		)
	)
	(wire
		(pts
			(xy 127 124.46) (xy 127 125.73)
		)
		(stroke
			(width 0)
			(type default)
		)
	)
	(wire
		(pts
			(xy 349.25 205.74) (xy 349.25 208.28)
		)
		(stroke
			(width 0)
			(type default)
		)
	)
	(bus
		(pts
			(xy 46.99 199.39) (xy 46.99 201.93)
		)
		(stroke
			(width 0)
			(type default)
		)
	)
	(wire
		(pts
			(xy 140.97 76.2) (xy 140.97 72.39)
		)
		(stroke
			(width 0)
			(type default)
		)
	)
	(wire
		(pts
			(xy 120.65 123.19) (xy 120.65 124.46)
		)
		(stroke
			(width 0)
			(type default)
		)
	)
	(wire
		(pts
			(xy 143.51 113.03) (xy 143.51 129.54)
		)
		(stroke
			(width 0)
			(type default)
		)
	)
	(wire
		(pts
			(xy 97.79 130.81) (xy 97.79 132.08)
		)
		(stroke
			(width 0)
			(type default)
		)
	)
	(wire
		(pts
			(xy 317.5 195.58) (xy 330.2 195.58)
		)
		(stroke
			(width 0)
			(type default)
		)
	)
	(wire
		(pts
			(xy 147.32 233.68) (xy 151.13 233.68)
		)
		(stroke
			(width 0)
			(type default)
		)
	)
	(wire
		(pts
			(xy 147.32 257.81) (xy 151.13 257.81)
		)
		(stroke
			(width 0)
			(type default)
		)
	)
	(wire
		(pts
			(xy 119.38 143.51) (xy 135.89 143.51)
		)
		(stroke
			(width 0)
			(type default)
		)
	)
	(wire
		(pts
			(xy 165.1 137.16) (xy 166.37 137.16)
		)
		(stroke
			(width 0)
			(type default)
		)
	)
	(wire
		(pts
			(xy 27.94 242.57) (xy 27.94 246.38)
		)
		(stroke
			(width 0)
			(type default)
		)
	)
	(wire
		(pts
			(xy 148.59 76.2) (xy 156.21 76.2)
		)
		(stroke
			(width 0)
			(type default)
		)
	)
	(polyline
		(pts
			(xy 90.17 89.535) (xy 229.87 89.535)
		)
		(stroke
			(width 0)
			(type dash)
		)
	)
	(wire
		(pts
			(xy 184.15 134.62) (xy 201.93 134.62)
		)
		(stroke
			(width 0)
			(type default)
		)
	)
	(wire
		(pts
			(xy 349.25 208.28) (xy 351.79 208.28)
		)
		(stroke
			(width 0)
			(type default)
		)
	)
	(wire
		(pts
			(xy 313.69 177.8) (xy 327.66 177.8)
		)
		(stroke
			(width 0)
			(type default)
		)
	)
	(wire
		(pts
			(xy 331.47 86.36) (xy 351.79 86.36)
		)
		(stroke
			(width 0)
			(type default)
		)
	)
	(wire
		(pts
			(xy 331.47 88.9) (xy 351.79 88.9)
		)
		(stroke
			(width 0)
			(type default)
		)
	)
	(wire
		(pts
			(xy 151.13 186.69) (xy 153.67 186.69)
		)
		(stroke
			(width 0)
			(type default)
		)
	)
	(wire
		(pts
			(xy 191.77 72.39) (xy 195.58 72.39)
		)
		(stroke
			(width 0)
			(type default)
		)
	)
	(wire
		(pts
			(xy 135.89 143.51) (xy 135.89 134.62)
		)
		(stroke
			(width 0)
			(type default)
		)
	)
	(wire
		(pts
			(xy 151.13 257.81) (xy 153.67 257.81)
		)
		(stroke
			(width 0)
			(type default)
		)
	)
	(wire
		(pts
			(xy 132.08 111.76) (xy 132.08 113.03)
		)
		(stroke
			(width 0)
			(type default)
		)
	)
	(wire
		(pts
			(xy 34.29 69.85) (xy 45.72 69.85)
		)
		(stroke
			(width 0)
			(type default)
		)
	)
	(wire
		(pts
			(xy 349.25 121.92) (xy 351.79 121.92)
		)
		(stroke
			(width 0)
			(type default)
		)
	)
	(bus
		(pts
			(xy 330.2 128.27) (xy 330.2 130.81)
		)
		(stroke
			(width 0)
			(type default)
		)
	)
	(wire
		(pts
			(xy 27.94 236.22) (xy 27.94 237.49)
		)
		(stroke
			(width 0)
			(type default)
		)
	)
	(wire
		(pts
			(xy 331.47 93.98) (xy 351.79 93.98)
		)
		(stroke
			(width 0)
			(type default)
		)
	)
	(wire
		(pts
			(xy 48.26 198.12) (xy 53.34 198.12)
		)
		(stroke
			(width 0)
			(type default)
		)
	)
	(wire
		(pts
			(xy 140.97 72.39) (xy 143.51 72.39)
		)
		(stroke
			(width 0)
			(type default)
		)
	)
	(wire
		(pts
			(xy 132.08 113.03) (xy 140.97 113.03)
		)
		(stroke
			(width 0)
			(type default)
		)
	)
	(wire
		(pts
			(xy 292.1 177.8) (xy 308.61 177.8)
		)
		(stroke
			(width 0)
			(type default)
		)
	)
	(wire
		(pts
			(xy 303.53 175.26) (xy 316.23 175.26)
		)
		(stroke
			(width 0)
			(type default)
		)
	)
	(wire
		(pts
			(xy 66.04 102.87) (xy 66.04 105.41)
		)
		(stroke
			(width 0)
			(type default)
		)
	)
	(wire
		(pts
			(xy 48.26 205.74) (xy 53.34 205.74)
		)
		(stroke
			(width 0)
			(type default)
		)
	)
	(bus
		(pts
			(xy 330.2 151.13) (xy 330.2 152.4)
		)
		(stroke
			(width 0)
			(type default)
		)
	)
	(wire
		(pts
			(xy 146.05 62.23) (xy 146.05 63.5)
		)
		(stroke
			(width 0)
			(type default)
		)
	)
	(wire
		(pts
			(xy 166.37 129.54) (xy 165.1 129.54)
		)
		(stroke
			(width 0)
			(type default)
		)
	)
	(bus
		(pts
			(xy 330.2 87.63) (xy 330.2 90.17)
		)
		(stroke
			(width 0)
			(type default)
		)
	)
	(wire
		(pts
			(xy 161.29 72.39) (xy 177.8 72.39)
		)
		(stroke
			(width 0)
			(type default)
		)
	)
	(wire
		(pts
			(xy 266.7 215.9) (xy 266.7 218.44)
		)
		(stroke
			(width 0)
			(type default)
		)
	)
	(wire
		(pts
			(xy 331.47 91.44) (xy 351.79 91.44)
		)
		(stroke
			(width 0)
			(type default)
		)
	)
	(wire
		(pts
			(xy 318.77 180.34) (xy 316.23 180.34)
		)
		(stroke
			(width 0)
			(type default)
		)
	)
	(bus
		(pts
			(xy 46.99 204.47) (xy 46.99 207.01)
		)
		(stroke
			(width 0)
			(type default)
		)
	)
	(wire
		(pts
			(xy 349.25 152.4) (xy 349.25 205.74)
		)
		(stroke
			(width 0)
			(type default)
		)
	)
	(wire
		(pts
			(xy 158.75 238.76) (xy 158.75 240.03)
		)
		(stroke
			(width 0)
			(type default)
		)
	)
	(wire
		(pts
			(xy 195.58 55.88) (xy 200.66 55.88)
		)
		(stroke
			(width 0)
			(type default)
		)
	)
	(wire
		(pts
			(xy 140.97 113.03) (xy 140.97 123.19)
		)
		(stroke
			(width 0)
			(type default)
		)
	)
	(wire
		(pts
			(xy 49.53 68.58) (xy 49.53 69.85)
		)
		(stroke
			(width 0)
			(type default)
		)
	)
	(wire
		(pts
			(xy 165.1 134.62) (xy 184.15 134.62)
		)
		(stroke
			(width 0)
			(type default)
		)
	)
	(wire
		(pts
			(xy 135.89 134.62) (xy 144.78 134.62)
		)
		(stroke
			(width 0)
			(type default)
		)
	)
	(wire
		(pts
			(xy 331.47 81.28) (xy 351.79 81.28)
		)
		(stroke
			(width 0)
			(type default)
		)
	)
	(wire
		(pts
			(xy 190.5 130.81) (xy 190.5 132.08)
		)
		(stroke
			(width 0)
			(type default)
		)
	)
	(bus
		(pts
			(xy 328.93 107.95) (xy 322.58 107.95)
		)
		(stroke
			(width 0)
			(type default)
		)
	)
	(wire
		(pts
			(xy 331.47 101.6) (xy 351.79 101.6)
		)
		(stroke
			(width 0)
			(type default)
		)
	)
	(wire
		(pts
			(xy 97.79 132.08) (xy 107.95 132.08)
		)
		(stroke
			(width 0)
			(type default)
		)
	)
	(wire
		(pts
			(xy 349.25 144.78) (xy 349.25 152.4)
		)
		(stroke
			(width 0)
			(type default)
		)
	)
	(wire
		(pts
			(xy 306.07 195.58) (xy 306.07 201.93)
		)
		(stroke
			(width 0)
			(type default)
		)
	)
	(wire
		(pts
			(xy 55.88 76.2) (xy 55.88 77.47)
		)
		(stroke
			(width 0)
			(type default)
		)
	)
	(bus
		(pts
			(xy 330.2 133.35) (xy 330.2 135.89)
		)
		(stroke
			(width 0)
			(type default)
		)
	)
	(wire
		(pts
			(xy 349.25 144.78) (xy 351.79 144.78)
		)
		(stroke
			(width 0)
			(type default)
		)
	)
	(wire
		(pts
			(xy 349.25 208.28) (xy 349.25 209.55)
		)
		(stroke
			(width 0)
			(type default)
		)
	)
	(wire
		(pts
			(xy 41.91 222.25) (xy 41.91 223.52)
		)
		(stroke
			(width 0)
			(type default)
		)
	)
	(wire
		(pts
			(xy 306.07 195.58) (xy 317.5 195.58)
		)
		(stroke
			(width 0)
			(type default)
		)
	)
	(wire
		(pts
			(xy 331.47 83.82) (xy 351.79 83.82)
		)
		(stroke
			(width 0)
			(type default)
		)
	)
	(wire
		(pts
			(xy 49.53 69.85) (xy 55.88 69.85)
		)
		(stroke
			(width 0)
			(type default)
		)
	)
	(wire
		(pts
			(xy 261.62 157.48) (xy 279.4 157.48)
		)
		(stroke
			(width 0)
			(type default)
		)
	)
	(wire
		(pts
			(xy 151.13 209.55) (xy 151.13 210.82)
		)
		(stroke
			(width 0)
			(type default)
		)
	)
	(wire
		(pts
			(xy 330.2 207.01) (xy 330.2 209.55)
		)
		(stroke
			(width 0)
			(type default)
		)
	)
	(bus
		(pts
			(xy 330.2 92.71) (xy 330.2 95.25)
		)
		(stroke
			(width 0)
			(type default)
		)
	)
	(wire
		(pts
			(xy 203.2 72.39) (xy 210.82 72.39)
		)
		(stroke
			(width 0)
			(type default)
		)
	)
	(wire
		(pts
			(xy 308.61 177.8) (xy 308.61 180.34)
		)
		(stroke
			(width 0)
			(type default)
		)
	)
	(wire
		(pts
			(xy 203.2 76.2) (xy 210.82 76.2)
		)
		(stroke
			(width 0)
			(type default)
		)
	)
	(wire
		(pts
			(xy 331.47 147.32) (xy 351.79 147.32)
		)
		(stroke
			(width 0)
			(type default)
		)
	)
	(wire
		(pts
			(xy 45.72 69.85) (xy 49.53 69.85)
		)
		(stroke
			(width 0)
			(type default)
		)
	)
	(wire
		(pts
			(xy 349.25 99.06) (xy 349.25 106.68)
		)
		(stroke
			(width 0)
			(type default)
		)
	)
	(wire
		(pts
			(xy 266.7 223.52) (xy 266.7 224.79)
		)
		(stroke
			(width 0)
			(type default)
		)
	)
	(wire
		(pts
			(xy 303.53 175.26) (xy 303.53 180.34)
		)
		(stroke
			(width 0)
			(type default)
		)
	)
	(wire
		(pts
			(xy 127 134.62) (xy 135.89 134.62)
		)
		(stroke
			(width 0)
			(type default)
		)
	)
	(wire
		(pts
			(xy 337.82 200.66) (xy 337.82 201.93)
		)
		(stroke
			(width 0)
			(type default)
		)
	)
	(wire
		(pts
			(xy 323.85 180.34) (xy 351.79 180.34)
		)
		(stroke
			(width 0)
			(type default)
		)
	)
	(wire
		(pts
			(xy 102.87 130.81) (xy 102.87 134.62)
		)
		(stroke
			(width 0)
			(type default)
		)
	)
	(bus
		(pts
			(xy 46.99 208.28) (xy 45.72 209.55)
		)
		(stroke
			(width 0)
			(type default)
		)
	)
	(wire
		(pts
			(xy 193.04 76.2) (xy 193.04 77.47)
		)
		(stroke
			(width 0)
			(type default)
		)
	)
	(bus
		(pts
			(xy 330.2 82.55) (xy 330.2 85.09)
		)
		(stroke
			(width 0)
			(type default)
		)
	)
	(wire
		(pts
			(xy 142.24 55.88) (xy 146.05 55.88)
		)
		(stroke
			(width 0)
			(type default)
		)
	)
	(wire
		(pts
			(xy 184.15 124.46) (xy 190.5 124.46)
		)
		(stroke
			(width 0)
			(type default)
		)
	)
	(bus
		(pts
			(xy 46.99 191.77) (xy 46.99 194.31)
		)
		(stroke
			(width 0)
			(type default)
		)
	)
	(bus
		(pts
			(xy 46.99 207.01) (xy 46.99 208.28)
		)
		(stroke
			(width 0)
			(type default)
		)
	)
	(wire
		(pts
			(xy 175.26 114.3) (xy 175.26 115.57)
		)
		(stroke
			(width 0)
			(type default)
		)
	)
	(wire
		(pts
			(xy 120.65 68.58) (xy 123.19 68.58)
		)
		(stroke
			(width 0)
			(type default)
		)
	)
	(wire
		(pts
			(xy 316.23 175.26) (xy 318.77 175.26)
		)
		(stroke
			(width 0)
			(type default)
		)
	)
	(wire
		(pts
			(xy 200.66 55.88) (xy 200.66 57.15)
		)
		(stroke
			(width 0)
			(type default)
		)
	)
	(wire
		(pts
			(xy 142.24 68.58) (xy 142.24 55.88)
		)
		(stroke
			(width 0)
			(type default)
		)
	)
	(wire
		(pts
			(xy 190.5 113.03) (xy 190.5 124.46)
		)
		(stroke
			(width 0)
			(type default)
		)
	)
	(wire
		(pts
			(xy 66.04 91.44) (xy 66.04 97.79)
		)
		(stroke
			(width 0)
			(type default)
		)
	)
	(wire
		(pts
			(xy 201.93 132.08) (xy 190.5 132.08)
		)
		(stroke
			(width 0)
			(type default)
		)
	)
	(wire
		(pts
			(xy 323.85 200.66) (xy 337.82 200.66)
		)
		(stroke
			(width 0)
			(type default)
		)
	)
	(bus
		(pts
			(xy 46.99 194.31) (xy 46.99 196.85)
		)
		(stroke
			(width 0)
			(type default)
		)
	)
	(polyline
		(pts
			(xy 90.17 153.035) (xy 229.87 153.035)
		)
		(stroke
			(width 0)
			(type dash)
		)
	)
	(wire
		(pts
			(xy 289.56 157.48) (xy 298.45 157.48)
		)
		(stroke
			(width 0)
			(type default)
		)
	)
	(bus
		(pts
			(xy 330.2 97.79) (xy 330.2 102.87)
		)
		(stroke
			(width 0)
			(type default)
		)
	)
	(wire
		(pts
			(xy 132.08 119.38) (xy 132.08 120.65)
		)
		(stroke
			(width 0)
			(type default)
		)
	)
	(wire
		(pts
			(xy 323.85 175.26) (xy 351.79 175.26)
		)
		(stroke
			(width 0)
			(type default)
		)
	)
	(wire
		(pts
			(xy 259.08 199.39) (xy 259.08 210.82)
		)
		(stroke
			(width 0)
			(type default)
		)
	)
	(wire
		(pts
			(xy 41.91 228.6) (xy 41.91 231.14)
		)
		(stroke
			(width 0)
			(type default)
		)
	)
	(polyline
		(pts
			(xy 229.87 12.065) (xy 229.87 285.115)
		)
		(stroke
			(width 0)
			(type dash)
		)
	)
	(wire
		(pts
			(xy 349.25 106.68) (xy 349.25 114.3)
		)
		(stroke
			(width 0)
			(type default)
		)
	)
	(wire
		(pts
			(xy 331.47 129.54) (xy 351.79 129.54)
		)
		(stroke
			(width 0)
			(type default)
		)
	)
	(bus
		(pts
			(xy 330.2 80.01) (xy 330.2 82.55)
		)
		(stroke
			(width 0)
			(type default)
		)
	)
	(wire
		(pts
			(xy 175.26 105.41) (xy 175.26 114.3)
		)
		(stroke
			(width 0)
			(type default)
		)
	)
	(wire
		(pts
			(xy 331.47 149.86) (xy 351.79 149.86)
		)
		(stroke
			(width 0)
			(type default)
		)
	)
	(wire
		(pts
			(xy 55.88 69.85) (xy 62.23 69.85)
		)
		(stroke
			(width 0)
			(type default)
		)
	)
	(wire
		(pts
			(xy 330.2 195.58) (xy 330.2 201.93)
		)
		(stroke
			(width 0)
			(type default)
		)
	)
	(wire
		(pts
			(xy 303.53 200.66) (xy 311.15 200.66)
		)
		(stroke
			(width 0)
			(type default)
		)
	)
	(wire
		(pts
			(xy 27.94 74.93) (xy 27.94 77.47)
		)
		(stroke
			(width 0)
			(type default)
		)
	)
	(polyline
		(pts
			(xy 12.065 128.905) (xy 90.17 128.905)
		)
		(stroke
			(width 0)
			(type dash)
		)
	)
	(wire
		(pts
			(xy 158.75 262.89) (xy 158.75 264.16)
		)
		(stroke
			(width 0)
			(type default)
		)
	)
	(wire
		(pts
			(xy 351.79 99.06) (xy 349.25 99.06)
		)
		(stroke
			(width 0)
			(type default)
		)
	)
	(wire
		(pts
			(xy 317.5 200.66) (xy 311.15 200.66)
		)
		(stroke
			(width 0)
			(type default)
		)
	)
	(wire
		(pts
			(xy 331.47 139.7) (xy 351.79 139.7)
		)
		(stroke
			(width 0)
			(type default)
		)
	)
	(wire
		(pts
			(xy 337.82 200.66) (xy 342.9 200.66)
		)
		(stroke
			(width 0)
			(type default)
		)
	)
	(wire
		(pts
			(xy 114.3 143.51) (xy 101.6 143.51)
		)
		(stroke
			(width 0)
			(type default)
		)
	)
	(wire
		(pts
			(xy 71.12 227.33) (xy 71.12 228.6)
		)
		(stroke
			(width 0)
			(type default)
		)
	)
	(wire
		(pts
			(xy 67.31 69.85) (xy 73.66 69.85)
		)
		(stroke
			(width 0)
			(type default)
		)
	)
	(wire
		(pts
			(xy 113.03 134.62) (xy 127 134.62)
		)
		(stroke
			(width 0)
			(type default)
		)
	)
	(wire
		(pts
			(xy 151.13 256.54) (xy 151.13 257.81)
		)
		(stroke
			(width 0)
			(type default)
		)
	)
	(wire
		(pts
			(xy 140.97 113.03) (xy 143.51 113.03)
		)
		(stroke
			(width 0)
			(type default)
		)
	)
	(wire
		(pts
			(xy 106.68 72.39) (xy 123.19 72.39)
		)
		(stroke
			(width 0)
			(type default)
		)
	)
	(wire
		(pts
			(xy 27.94 72.39) (xy 27.94 74.93)
		)
		(stroke
			(width 0)
			(type default)
		)
	)
	(wire
		(pts
			(xy 349.25 152.4) (xy 351.79 152.4)
		)
		(stroke
			(width 0)
			(type default)
		)
	)
	(wire
		(pts
			(xy 175.26 120.65) (xy 175.26 121.92)
		)
		(stroke
			(width 0)
			(type default)
		)
	)
	(bus
		(pts
			(xy 330.2 135.89) (xy 330.2 138.43)
		)
		(stroke
			(width 0)
			(type default)
		)
	)
	(wire
		(pts
			(xy 266.7 207.01) (xy 266.7 210.82)
		)
		(stroke
			(width 0)
			(type default)
		)
	)
	(bus
		(pts
			(xy 330.2 90.17) (xy 330.2 92.71)
		)
		(stroke
			(width 0)
			(type default)
		)
	)
	(wire
		(pts
			(xy 151.13 232.41) (xy 151.13 233.68)
		)
		(stroke
			(width 0)
			(type default)
		)
	)
	(wire
		(pts
			(xy 26.67 69.85) (xy 34.29 69.85)
		)
		(stroke
			(width 0)
			(type default)
		)
	)
	(wire
		(pts
			(xy 331.47 78.74) (xy 351.79 78.74)
		)
		(stroke
			(width 0)
			(type default)
		)
	)
	(wire
		(pts
			(xy 331.47 124.46) (xy 351.79 124.46)
		)
		(stroke
			(width 0)
			(type default)
		)
	)
	(wire
		(pts
			(xy 34.29 77.47) (xy 34.29 76.2)
		)
		(stroke
			(width 0)
			(type default)
		)
	)
	(wire
		(pts
			(xy 331.47 134.62) (xy 351.79 134.62)
		)
		(stroke
			(width 0)
			(type default)
		)
	)
	(wire
		(pts
			(xy 41.91 236.22) (xy 41.91 238.76)
		)
		(stroke
			(width 0)
			(type default)
		)
	)
	(wire
		(pts
			(xy 173.99 73.66) (xy 173.99 68.58)
		)
		(stroke
			(width 0)
			(type default)
		)
	)
	(wire
		(pts
			(xy 158.75 215.9) (xy 158.75 217.17)
		)
		(stroke
			(width 0)
			(type default)
		)
	)
	(wire
		(pts
			(xy 308.61 185.42) (xy 308.61 186.69)
		)
		(stroke
			(width 0)
			(type default)
		)
	)
	(bus
		(pts
			(xy 330.2 143.51) (xy 330.2 148.59)
		)
		(stroke
			(width 0)
			(type default)
		)
	)
	(wire
		(pts
			(xy 120.65 78.74) (xy 120.65 80.01)
		)
		(stroke
			(width 0)
			(type default)
		)
	)
	(wire
		(pts
			(xy 27.94 246.38) (xy 35.56 246.38)
		)
		(stroke
			(width 0)
			(type default)
		)
	)
	(wire
		(pts
			(xy 107.95 134.62) (xy 102.87 134.62)
		)
		(stroke
			(width 0)
			(type default)
		)
	)
	(wire
		(pts
			(xy 351.79 198.12) (xy 351.79 195.58)
		)
		(stroke
			(width 0)
			(type default)
		)
	)
	(wire
		(pts
			(xy 151.13 185.42) (xy 151.13 186.69)
		)
		(stroke
			(width 0)
			(type default)
		)
	)
	(wire
		(pts
			(xy 148.59 72.39) (xy 156.21 72.39)
		)
		(stroke
			(width 0)
			(type default)
		)
	)
	(wire
		(pts
			(xy 45.72 76.2) (xy 45.72 77.47)
		)
		(stroke
			(width 0)
			(type default)
		)
	)
	(wire
		(pts
			(xy 137.16 137.16) (xy 137.16 130.81)
		)
		(stroke
			(width 0)
			(type default)
		)
	)
	(wire
		(pts
			(xy 26.67 74.93) (xy 27.94 74.93)
		)
		(stroke
			(width 0)
			(type default)
		)
	)
	(wire
		(pts
			(xy 165.1 132.08) (xy 190.5 132.08)
		)
		(stroke
			(width 0)
			(type default)
		)
	)
	(wire
		(pts
			(xy 45.72 68.58) (xy 45.72 69.85)
		)
		(stroke
			(width 0)
			(type default)
		)
	)
	(wire
		(pts
			(xy 48.26 193.04) (xy 53.34 193.04)
		)
		(stroke
			(width 0)
			(type default)
		)
	)
	(bus
		(pts
			(xy 46.99 196.85) (xy 46.99 199.39)
		)
		(stroke
			(width 0)
			(type default)
		)
	)
	(wire
		(pts
			(xy 175.26 114.3) (xy 166.37 114.3)
		)
		(stroke
			(width 0)
			(type default)
		)
	)
	(wire
		(pts
			(xy 332.74 177.8) (xy 351.79 177.8)
		)
		(stroke
			(width 0)
			(type default)
		)
	)
	(wire
		(pts
			(xy 331.47 132.08) (xy 351.79 132.08)
		)
		(stroke
			(width 0)
			(type default)
		)
	)
	(wire
		(pts
			(xy 259.08 215.9) (xy 259.08 218.44)
		)
		(stroke
			(width 0)
			(type default)
		)
	)
	(wire
		(pts
			(xy 195.58 76.2) (xy 195.58 72.39)
		)
		(stroke
			(width 0)
			(type default)
		)
	)
	(wire
		(pts
			(xy 96.52 132.08) (xy 97.79 132.08)
		)
		(stroke
			(width 0)
			(type default)
		)
	)
	(wire
		(pts
			(xy 284.48 162.56) (xy 289.56 162.56)
		)
		(stroke
			(width 0)
			(type default)
		)
	)
	(wire
		(pts
			(xy 327.66 182.88) (xy 313.69 182.88)
		)
		(stroke
			(width 0)
			(type default)
		)
	)
	(wire
		(pts
			(xy 137.16 72.39) (xy 140.97 72.39)
		)
		(stroke
			(width 0)
			(type default)
		)
	)
	(wire
		(pts
			(xy 48.26 195.58) (xy 53.34 195.58)
		)
		(stroke
			(width 0)
			(type default)
		)
	)
	(wire
		(pts
			(xy 349.25 114.3) (xy 351.79 114.3)
		)
		(stroke
			(width 0)
			(type default)
		)
	)
	(wire
		(pts
			(xy 173.99 78.74) (xy 173.99 80.01)
		)
		(stroke
			(width 0)
			(type default)
		)
	)
	(bus
		(pts
			(xy 330.2 105.41) (xy 330.2 106.68)
		)
		(stroke
			(width 0)
			(type default)
		)
	)
	(wire
		(pts
			(xy 311.15 208.28) (xy 311.15 207.01)
		)
		(stroke
			(width 0)
			(type default)
		)
	)
	(wire
		(pts
			(xy 337.82 207.01) (xy 337.82 209.55)
		)
		(stroke
			(width 0)
			(type default)
		)
	)
	(wire
		(pts
			(xy 166.37 137.16) (xy 166.37 138.43)
		)
		(stroke
			(width 0)
			(type default)
		)
	)
	(wire
		(pts
			(xy 279.4 157.48) (xy 279.4 165.1)
		)
		(stroke
			(width 0)
			(type default)
		)
	)
	(wire
		(pts
			(xy 146.05 55.88) (xy 146.05 57.15)
		)
		(stroke
			(width 0)
			(type default)
		)
	)
	(wire
		(pts
			(xy 143.51 129.54) (xy 144.78 129.54)
		)
		(stroke
			(width 0)
			(type default)
		)
	)
	(wire
		(pts
			(xy 158.75 191.77) (xy 158.75 193.04)
		)
		(stroke
			(width 0)
			(type default)
		)
	)
	(bus
		(pts
			(xy 46.99 201.93) (xy 46.99 204.47)
		)
		(stroke
			(width 0)
			(type default)
		)
	)
	(wire
		(pts
			(xy 138.43 77.47) (xy 138.43 76.2)
		)
		(stroke
			(width 0)
			(type default)
		)
	)
	(wire
		(pts
			(xy 184.15 124.46) (xy 184.15 125.73)
		)
		(stroke
			(width 0)
			(type default)
		)
	)
	(bus
		(pts
			(xy 330.2 148.59) (xy 330.2 151.13)
		)
		(stroke
			(width 0)
			(type default)
		)
	)
	(wire
		(pts
			(xy 332.74 182.88) (xy 351.79 182.88)
		)
		(stroke
			(width 0)
			(type default)
		)
	)
	(wire
		(pts
			(xy 55.88 69.85) (xy 55.88 71.12)
		)
		(stroke
			(width 0)
			(type default)
		)
	)
	(wire
		(pts
			(xy 259.08 223.52) (xy 259.08 224.79)
		)
		(stroke
			(width 0)
			(type default)
		)
	)
	(wire
		(pts
			(xy 120.65 124.46) (xy 120.65 125.73)
		)
		(stroke
			(width 0)
			(type default)
		)
	)
	(wire
		(pts
			(xy 331.47 104.14) (xy 351.79 104.14)
		)
		(stroke
			(width 0)
			(type default)
		)
	)
	(wire
		(pts
			(xy 137.16 123.19) (xy 140.97 123.19)
		)
		(stroke
			(width 0)
			(type default)
		)
	)
	(wire
		(pts
			(xy 303.53 157.48) (xy 351.79 157.48)
		)
		(stroke
			(width 0)
			(type default)
		)
	)
	(wire
		(pts
			(xy 147.32 210.82) (xy 151.13 210.82)
		)
		(stroke
			(width 0)
			(type default)
		)
	)
	(wire
		(pts
			(xy 331.47 142.24) (xy 351.79 142.24)
		)
		(stroke
			(width 0)
			(type default)
		)
	)
	(wire
		(pts
			(xy 26.67 72.39) (xy 27.94 72.39)
		)
		(stroke
			(width 0)
			(type default)
		)
	)
	(wire
		(pts
			(xy 195.58 72.39) (xy 198.12 72.39)
		)
		(stroke
			(width 0)
			(type default)
		)
	)
	(wire
		(pts
			(xy 349.25 106.68) (xy 351.79 106.68)
		)
		(stroke
			(width 0)
			(type default)
		)
	)
	(wire
		(pts
			(xy 120.65 124.46) (xy 127 124.46)
		)
		(stroke
			(width 0)
			(type default)
		)
	)
	(wire
		(pts
			(xy 313.69 182.88) (xy 313.69 177.8)
		)
		(stroke
			(width 0)
			(type default)
		)
	)
	(bus
		(pts
			(xy 330.2 130.81) (xy 330.2 133.35)
		)
		(stroke
			(width 0)
			(type default)
		)
	)
	(bus
		(pts
			(xy 330.2 140.97) (xy 330.2 143.51)
		)
		(stroke
			(width 0)
			(type default)
		)
	)
	(wire
		(pts
			(xy 66.04 110.49) (xy 66.04 111.76)
		)
		(stroke
			(width 0)
			(type default)
		)
	)
	(wire
		(pts
			(xy 351.79 203.2) (xy 351.79 200.66)
		)
		(stroke
			(width 0)
			(type default)
		)
	)
	(wire
		(pts
			(xy 349.25 114.3) (xy 349.25 121.92)
		)
		(stroke
			(width 0)
			(type default)
		)
	)
	(bus
		(pts
			(xy 330.2 125.73) (xy 330.2 128.27)
		)
		(stroke
			(width 0)
			(type default)
		)
	)
	(wire
		(pts
			(xy 200.66 62.23) (xy 200.66 63.5)
		)
		(stroke
			(width 0)
			(type default)
		)
	)
	(wire
		(pts
			(xy 173.99 68.58) (xy 177.8 68.58)
		)
		(stroke
			(width 0)
			(type default)
		)
	)
	(bus
		(pts
			(xy 330.2 95.25) (xy 330.2 97.79)
		)
		(stroke
			(width 0)
			(type default)
		)
	)
	(bus
		(pts
			(xy 330.2 106.68) (xy 328.93 107.95)
		)
		(stroke
			(width 0)
			(type default)
		)
	)
	(wire
		(pts
			(xy 335.28 195.58) (xy 351.79 195.58)
		)
		(stroke
			(width 0)
			(type default)
		)
	)
	(wire
		(pts
			(xy 316.23 180.34) (xy 316.23 175.26)
		)
		(stroke
			(width 0)
			(type default)
		)
	)
	(wire
		(pts
			(xy 34.29 69.85) (xy 34.29 71.12)
		)
		(stroke
			(width 0)
			(type default)
		)
	)
	(wire
		(pts
			(xy 41.91 248.92) (xy 41.91 255.27)
		)
		(stroke
			(width 0)
			(type default)
		)
	)
	(bus
		(pts
			(xy 330.2 138.43) (xy 330.2 140.97)
		)
		(stroke
			(width 0)
			(type default)
		)
	)
	(bus
		(pts
			(xy 330.2 102.87) (xy 330.2 105.41)
		)
		(stroke
			(width 0)
			(type default)
		)
	)
	(wire
		(pts
			(xy 342.9 200.66) (xy 351.79 200.66)
		)
		(stroke
			(width 0)
			(type default)
		)
	)
	(wire
		(pts
			(xy 151.13 210.82) (xy 153.67 210.82)
		)
		(stroke
			(width 0)
			(type default)
		)
	)
	(wire
		(pts
			(xy 132.08 113.03) (xy 132.08 114.3)
		)
		(stroke
			(width 0)
			(type default)
		)
	)
	(wire
		(pts
			(xy 134.62 139.7) (xy 134.62 132.08)
		)
		(stroke
			(width 0)
			(type default)
		)
	)
	(wire
		(pts
			(xy 331.47 137.16) (xy 351.79 137.16)
		)
		(stroke
			(width 0)
			(type default)
		)
	)
	(bus
		(pts
			(xy 328.93 153.67) (xy 322.58 153.67)
		)
		(stroke
			(width 0)
			(type default)
		)
	)
	(wire
		(pts
			(xy 120.65 130.81) (xy 120.65 132.08)
		)
		(stroke
			(width 0)
			(type default)
		)
	)
	(wire
		(pts
			(xy 20.32 246.38) (xy 27.94 246.38)
		)
		(stroke
			(width 0)
			(type default)
		)
	)
	(wire
		(pts
			(xy 120.65 132.08) (xy 134.62 132.08)
		)
		(stroke
			(width 0)
			(type default)
		)
	)
	(wire
		(pts
			(xy 151.13 233.68) (xy 153.67 233.68)
		)
		(stroke
			(width 0)
			(type default)
		)
	)
	(wire
		(pts
			(xy 311.15 200.66) (xy 311.15 201.93)
		)
		(stroke
			(width 0)
			(type default)
		)
	)
	(wire
		(pts
			(xy 330.2 195.58) (xy 335.28 195.58)
		)
		(stroke
			(width 0)
			(type default)
		)
	)
	(wire
		(pts
			(xy 294.64 195.58) (xy 306.07 195.58)
		)
		(stroke
			(width 0)
			(type default)
		)
	)
	(wire
		(pts
			(xy 102.87 134.62) (xy 96.52 134.62)
		)
		(stroke
			(width 0)
			(type default)
		)
	)
	(wire
		(pts
			(xy 184.15 130.81) (xy 184.15 134.62)
		)
		(stroke
			(width 0)
			(type default)
		)
	)
	(wire
		(pts
			(xy 137.16 68.58) (xy 142.24 68.58)
		)
		(stroke
			(width 0)
			(type default)
		)
	)
	(wire
		(pts
			(xy 279.4 157.48) (xy 289.56 157.48)
		)
		(stroke
			(width 0)
			(type default)
		)
	)
	(wire
		(pts
			(xy 48.26 200.66) (xy 53.34 200.66)
		)
		(stroke
			(width 0)
			(type default)
		)
	)
	(label "FFC_3V3"
		(at 259.08 199.39 270)
		(effects
			(font
				(size 1.27 1.27)
			)
			(justify right bottom)
		)
	)
	(label "VSYNC_CAM0"
		(at 106.68 72.39 0)
		(effects
			(font
				(size 1.27 1.27)
			)
			(justify left bottom)
		)
	)
	(label "CSI0.CLK_P"
		(at 331.47 104.14 0)
		(effects
			(font
				(size 1.27 1.27)
			)
			(justify left bottom)
		)
	)
	(label "MFP1"
		(at 156.21 76.2 180)
		(effects
			(font
				(size 1.27 1.27)
			)
			(justify right bottom)
		)
	)
	(label "MFP1"
		(at 53.34 190.5 180)
		(effects
			(font
				(size 1.27 1.27)
			)
			(justify right bottom)
		)
	)
	(label "MFP0"
		(at 156.21 72.39 180)
		(effects
			(font
				(size 1.27 1.27)
			)
			(justify right bottom)
		)
	)
	(label "CSI0.D1_N"
		(at 331.47 88.9 0)
		(effects
			(font
				(size 1.27 1.27)
			)
			(justify left bottom)
		)
	)
	(label "CSI1.CLK_N"
		(at 331.47 147.32 0)
		(effects
			(font
				(size 1.27 1.27)
			)
			(justify left bottom)
		)
	)
	(label "MFP3"
		(at 53.34 195.58 180)
		(effects
			(font
				(size 1.27 1.27)
			)
			(justify right bottom)
		)
	)
	(label "SCL_CAM0"
		(at 337.82 177.8 0)
		(effects
			(font
				(size 1.27 1.27)
			)
			(justify left bottom)
		)
	)
	(label "MFP5"
		(at 53.34 200.66 180)
		(effects
			(font
				(size 1.27 1.27)
			)
			(justify right bottom)
		)
	)
	(label "VSYNC_CAM1"
		(at 261.62 162.56 0)
		(effects
			(font
				(size 1.27 1.27)
			)
			(justify left bottom)
		)
	)
	(label "CSI0.CLK_N"
		(at 331.47 101.6 0)
		(effects
			(font
				(size 1.27 1.27)
			)
			(justify left bottom)
		)
	)
	(label "SCL_CAM"
		(at 201.93 134.62 180)
		(effects
			(font
				(size 1.27 1.27)
			)
			(justify right bottom)
		)
	)
	(label "FFC_3V3"
		(at 190.5 113.03 270)
		(effects
			(font
				(size 1.27 1.27)
			)
			(justify right bottom)
		)
	)
	(label "MFP7"
		(at 53.34 203.2 180)
		(effects
			(font
				(size 1.27 1.27)
			)
			(justify right bottom)
		)
	)
	(label "VSYNC_CAM0"
		(at 261.62 157.48 0)
		(effects
			(font
				(size 1.27 1.27)
			)
			(justify left bottom)
		)
	)
	(label "CSI1.D0_N"
		(at 331.47 139.7 0)
		(effects
			(font
				(size 1.27 1.27)
			)
			(justify left bottom)
		)
	)
	(label "CSI1.D3_N"
		(at 331.47 124.46 0)
		(effects
			(font
				(size 1.27 1.27)
			)
			(justify left bottom)
		)
	)
	(label "CSI0.D2_P"
		(at 331.47 86.36 0)
		(effects
			(font
				(size 1.27 1.27)
			)
			(justify left bottom)
		)
	)
	(label "SDA_CAM1"
		(at 337.82 180.34 0)
		(effects
			(font
				(size 1.27 1.27)
			)
			(justify left bottom)
		)
	)
	(label "SCL_CAM"
		(at 292.1 177.8 0)
		(effects
			(font
				(size 1.27 1.27)
			)
			(justify left bottom)
		)
	)
	(label "CSI0.D2_N"
		(at 331.47 83.82 0)
		(effects
			(font
				(size 1.27 1.27)
			)
			(justify left bottom)
		)
	)
	(label "SDA_CAM0"
		(at 337.82 175.26 0)
		(effects
			(font
				(size 1.27 1.27)
			)
			(justify left bottom)
		)
	)
	(label "SCL_CAM1"
		(at 337.82 182.88 0)
		(effects
			(font
				(size 1.27 1.27)
			)
			(justify left bottom)
		)
	)
	(label "CSI0.D0_P"
		(at 331.47 96.52 0)
		(effects
			(font
				(size 1.27 1.27)
			)
			(justify left bottom)
		)
	)
	(label "CSI1.CLK_P"
		(at 331.47 149.86 0)
		(effects
			(font
				(size 1.27 1.27)
			)
			(justify left bottom)
		)
	)
	(label "CSI0.D1_P"
		(at 331.47 91.44 0)
		(effects
			(font
				(size 1.27 1.27)
			)
			(justify left bottom)
		)
	)
	(label "MFP8"
		(at 53.34 205.74 180)
		(effects
			(font
				(size 1.27 1.27)
			)
			(justify right bottom)
		)
	)
	(label "SDA_CAM"
		(at 201.93 132.08 180)
		(effects
			(font
				(size 1.27 1.27)
			)
			(justify right bottom)
		)
	)
	(label "MFP7"
		(at 101.6 139.7 0)
		(effects
			(font
				(size 1.27 1.27)
			)
			(justify left bottom)
		)
	)
	(label "FFC_3V3"
		(at 294.64 195.58 0)
		(effects
			(font
				(size 1.27 1.27)
			)
			(justify left bottom)
		)
	)
	(label "CSI1.D3_P"
		(at 331.47 127 0)
		(effects
			(font
				(size 1.27 1.27)
			)
			(justify left bottom)
		)
	)
	(label "CSI1.D1_N"
		(at 331.47 134.62 0)
		(effects
			(font
				(size 1.27 1.27)
			)
			(justify left bottom)
		)
	)
	(label "CSI0.D3_P"
		(at 331.47 81.28 0)
		(effects
			(font
				(size 1.27 1.27)
			)
			(justify left bottom)
		)
	)
	(label "SDA_CAM"
		(at 292.1 175.26 0)
		(effects
			(font
				(size 1.27 1.27)
			)
			(justify left bottom)
		)
	)
	(label "CSI1.D1_P"
		(at 331.47 137.16 0)
		(effects
			(font
				(size 1.27 1.27)
			)
			(justify left bottom)
		)
	)
	(label "DC_UNFUSED"
		(at 29.21 69.85 0)
		(effects
			(font
				(size 1.27 1.27)
			)
			(justify left bottom)
		)
	)
	(label "CSI1.D2_P"
		(at 331.47 132.08 0)
		(effects
			(font
				(size 1.27 1.27)
			)
			(justify left bottom)
		)
	)
	(label "CSI1.D2_N"
		(at 331.47 129.54 0)
		(effects
			(font
				(size 1.27 1.27)
			)
			(justify left bottom)
		)
	)
	(label "MFP3"
		(at 210.82 76.2 180)
		(effects
			(font
				(size 1.27 1.27)
			)
			(justify right bottom)
		)
	)
	(label "MFP8"
		(at 101.6 143.51 0)
		(effects
			(font
				(size 1.27 1.27)
			)
			(justify left bottom)
		)
	)
	(label "MFP4"
		(at 20.32 246.38 0)
		(effects
			(font
				(size 1.27 1.27)
			)
			(justify left bottom)
		)
	)
	(label "CSI0.D0_N"
		(at 331.47 93.98 0)
		(effects
			(font
				(size 1.27 1.27)
			)
			(justify left bottom)
		)
	)
	(label "MFP0"
		(at 53.34 187.96 180)
		(effects
			(font
				(size 1.27 1.27)
			)
			(justify right bottom)
		)
	)
	(label "FFC_3V3"
		(at 175.26 105.41 270)
		(effects
			(font
				(size 1.27 1.27)
			)
			(justify right bottom)
		)
	)
	(label "MFP4"
		(at 53.34 198.12 180)
		(effects
			(font
				(size 1.27 1.27)
			)
			(justify right bottom)
		)
	)
	(label "CSI0.D3_N"
		(at 331.47 78.74 0)
		(effects
			(font
				(size 1.27 1.27)
			)
			(justify left bottom)
		)
	)
	(label "MFP2"
		(at 210.82 72.39 180)
		(effects
			(font
				(size 1.27 1.27)
			)
			(justify right bottom)
		)
	)
	(label "VSYNC_CAM1"
		(at 161.29 72.39 0)
		(effects
			(font
				(size 1.27 1.27)
			)
			(justify left bottom)
		)
	)
	(label "DC_UNFUSED"
		(at 78.74 91.44 180)
		(effects
			(font
				(size 1.27 1.27)
			)
			(justify right bottom)
		)
	)
	(label "CSI1.D0_P"
		(at 331.47 142.24 0)
		(effects
			(font
				(size 1.27 1.27)
			)
			(justify left bottom)
		)
	)
	(label "MFP2"
		(at 53.34 193.04 180)
		(effects
			(font
				(size 1.27 1.27)
			)
			(justify right bottom)
		)
	)
	(global_label "VDDIO"
		(shape input)
		(at 27.94 236.22 90)
		(fields_autoplaced yes)
		(effects
			(font
				(size 1.27 1.27)
			)
			(justify left)
		)
		(property "Intersheetrefs" "${INTERSHEET_REFS}"
			(at 27.94 227.6709 90)
			(effects
				(font
					(size 1.27 1.27)
				)
				(justify left)
				(hide yes)
			)
		)
	)
	(hierarchical_label "SIOCP"
		(shape bidirectional)
		(at 147.32 233.68 180)
		(effects
			(font
				(size 1.27 1.27)
			)
			(justify right)
		)
	)
	(hierarchical_label "CSI1{CSI}"
		(shape input)
		(at 322.58 153.67 180)
		(effects
			(font
				(size 1.27 1.27)
			)
			(justify right)
		)
	)
	(hierarchical_label "PoCD"
		(shape input)
		(at 151.13 256.54 90)
		(effects
			(font
				(size 1.27 1.27)
			)
			(justify left)
		)
	)
	(hierarchical_label "PoCB"
		(shape input)
		(at 151.13 209.55 90)
		(effects
			(font
				(size 1.27 1.27)
			)
			(justify left)
		)
	)
	(hierarchical_label "CSI0{CSI}"
		(shape input)
		(at 322.58 107.95 180)
		(effects
			(font
				(size 1.27 1.27)
			)
			(justify right)
		)
	)
	(hierarchical_label "SIOAP"
		(shape bidirectional)
		(at 147.32 186.69 180)
		(effects
			(font
				(size 1.27 1.27)
			)
			(justify right)
		)
	)
	(hierarchical_label "SCL"
		(shape output)
		(at 96.52 134.62 180)
		(effects
			(font
				(size 1.27 1.27)
			)
			(justify right)
		)
	)
	(hierarchical_label "SDA"
		(shape bidirectional)
		(at 96.52 132.08 180)
		(effects
			(font
				(size 1.27 1.27)
			)
			(justify right)
		)
	)
	(hierarchical_label "FFC_5V"
		(shape output)
		(at 303.53 200.66 180)
		(effects
			(font
				(size 1.27 1.27)
			)
			(justify right)
		)
	)
	(hierarchical_label "FFC_5V"
		(shape output)
		(at 266.7 207.01 90)
		(effects
			(font
				(size 1.27 1.27)
			)
			(justify left)
		)
	)
	(hierarchical_label "MFP[0..8]"
		(shape bidirectional)
		(at 39.37 209.55 180)
		(effects
			(font
				(size 1.27 1.27)
			)
			(justify right)
		)
	)
	(hierarchical_label "SIOBP"
		(shape bidirectional)
		(at 147.32 210.82 180)
		(effects
			(font
				(size 1.27 1.27)
			)
			(justify right)
		)
	)
	(hierarchical_label "PoCA"
		(shape input)
		(at 151.13 185.42 90)
		(effects
			(font
				(size 1.27 1.27)
			)
			(justify left)
		)
	)
	(hierarchical_label "SIODP"
		(shape bidirectional)
		(at 147.32 257.81 180)
		(effects
			(font
				(size 1.27 1.27)
			)
			(justify right)
		)
	)
	(hierarchical_label "DC_IN"
		(shape output)
		(at 73.66 69.85 0)
		(effects
			(font
				(size 1.27 1.27)
			)
			(justify left)
		)
	)
	(hierarchical_label "PoCC"
		(shape input)
		(at 151.13 232.41 90)
		(effects
			(font
				(size 1.27 1.27)
			)
			(justify left)
		)
	)
	(symbol
		(lib_id "antmicroTVSDiodes:ESD5B5_0ST1G")
		(at 279.4 170.18 90)
		(unit 1)
		(exclude_from_sim no)
		(in_bom yes)
		(on_board yes)
		(dnp no)
		(property "Reference" "D6"
			(at 277.495 166.37 90)
			(effects
				(font
					(size 1.27 1.27)
					(thickness 0.15)
				)
				(justify left)
			)
		)
		(property "Value" "ESD5B5_0ST1G"
			(at 262.89 168.91 90)
			(effects
				(font
					(size 1.27 1.27)
					(thickness 0.15)
				)
				(justify right)
			)
		)
		(property "Footprint" "antmicro-footprints:SOD-523_NP"
			(at 289.56 144.78 0)
			(effects
				(font
					(size 1.27 1.27)
					(thickness 0.15)
				)
				(justify left bottom)
				(hide yes)
			)
		)
		(property "Datasheet" "https://www.onsemi.com/pdf/datasheet/esd5b5.0st1-d.pdf"
			(at 292.1 144.78 0)
			(effects
				(font
					(size 1.27 1.27)
					(thickness 0.15)
				)
				(justify left bottom)
				(hide yes)
			)
		)
		(property "Description" "Bidirectional TVS, 30 kV,  SOD-523, 5 V, 32 pF"
			(at 279.4 170.18 0)
			(effects
				(font
					(size 1.27 1.27)
				)
				(hide yes)
			)
		)
		(property "Manufacturer" "ON Semiconductor"
			(at 294.64 144.78 0)
			(effects
				(font
					(size 1.27 1.27)
					(thickness 0.15)
				)
				(justify left bottom)
				(hide yes)
			)
		)
		(property "MPN" "ESD5B5.0ST1G"
			(at 297.18 144.78 0)
			(effects
				(font
					(size 1.27 1.27)
					(thickness 0.15)
				)
				(justify left bottom)
				(hide yes)
			)
		)
		(property "Author" "Antmicro"
			(at 299.72 144.78 0)
			(effects
				(font
					(size 1.27 1.27)
					(thickness 0.15)
				)
				(justify left bottom)
				(hide yes)
			)
		)
		(property "License" "Apache-2.0"
			(at 302.26 144.78 0)
			(effects
				(font
					(size 1.27 1.27)
					(thickness 0.15)
				)
				(justify left bottom)
				(hide yes)
			)
		)
		(pin "1"
		)
		(pin "2"
		)
		(instances
			(project "gmsl-deserializer"
				(path ""
					(reference "D6")
					(unit 1)
				)
			)
		)
	)
	(symbol
		(lib_id "antmicroResistors0402:R_10k_0402")
		(at 137.16 130.81 90)
		(unit 1)
		(exclude_from_sim no)
		(in_bom yes)
		(on_board yes)
		(dnp no)
		(property "Reference" "R60"
			(at 138.43 127 90)
			(effects
				(font
					(size 1.27 1.27)
					(thickness 0.15)
				)
				(justify right)
			)
		)
		(property "Value" "R_10k_0402"
			(at 149.86 110.49 0)
			(effects
				(font
					(size 1.27 1.27)
					(thickness 0.15)
				)
				(justify left bottom)
				(hide yes)
			)
		)
		(property "Footprint" "antmicro-footprints:R_0402_1005Metric"
			(at 152.4 110.49 0)
			(effects
				(font
					(size 1.27 1.27)
					(thickness 0.15)
				)
				(justify left bottom)
				(hide yes)
			)
		)
		(property "Datasheet" "https://www.bourns.com/docs/product-datasheets/cr.pdf"
			(at 154.94 110.49 0)
			(effects
				(font
					(size 1.27 1.27)
					(thickness 0.15)
				)
				(justify left bottom)
				(hide yes)
			)
		)
		(property "Description" "SMD Chip Resistor, 10 kohm, ± 1%, 62.5 mW, 0402 [1005 Metric], Thick Film, General Purpose"
			(at 137.16 130.81 0)
			(effects
				(font
					(size 1.27 1.27)
				)
				(hide yes)
			)
		)
		(property "MPN" "CR0402-FX-1002GLF"
			(at 157.48 110.49 0)
			(effects
				(font
					(size 1.27 1.27)
					(thickness 0.15)
				)
				(justify left bottom)
				(hide yes)
			)
		)
		(property "Manufacturer" "Bourns"
			(at 160.02 110.49 0)
			(effects
				(font
					(size 1.27 1.27)
					(thickness 0.15)
				)
				(justify left bottom)
				(hide yes)
			)
		)
		(property "License" "Apache-2.0"
			(at 162.56 110.49 0)
			(effects
				(font
					(size 1.27 1.27)
					(thickness 0.15)
				)
				(justify left bottom)
				(hide yes)
			)
		)
		(property "Author" "Antmicro"
			(at 165.1 110.49 0)
			(effects
				(font
					(size 1.27 1.27)
					(thickness 0.15)
				)
				(justify left bottom)
				(hide yes)
			)
		)
		(property "Val" "10k"
			(at 138.43 129.54 90)
			(effects
				(font
					(size 1.27 1.27)
					(thickness 0.15)
				)
				(justify right)
			)
		)
		(property "Tolerance" "1%"
			(at 147.32 110.49 0)
			(effects
				(font
					(size 1.27 1.27)
				)
				(justify left bottom)
				(hide yes)
			)
		)
		(pin "1"
		)
		(pin "2"
		)
		(instances
			(project "gmsl-deserializer"
				(path ""
					(reference "R60")
					(unit 1)
				)
			)
		)
	)
	(symbol
		(lib_id "antmicroCapacitors0402:C_100n_0402")
		(at 175.26 120.65 270)
		(mirror x)
		(unit 1)
		(exclude_from_sim no)
		(in_bom yes)
		(on_board yes)
		(dnp no)
		(property "Reference" "C31"
			(at 173.355 116.84 90)
			(effects
				(font
					(size 1.27 1.27)
					(thickness 0.15)
				)
				(justify right)
			)
		)
		(property "Value" "C_100n_0402"
			(at 165.1 100.33 0)
			(effects
				(font
					(size 1.27 1.27)
					(thickness 0.15)
				)
				(justify left bottom)
				(hide yes)
			)
		)
		(property "Footprint" "antmicro-footprints:C_0402_1005Metric"
			(at 162.56 100.33 0)
			(effects
				(font
					(size 1.27 1.27)
					(thickness 0.15)
				)
				(justify left bottom)
				(hide yes)
			)
		)
		(property "Datasheet" "https://www.murata.com/products/productdetail?partno=GRM155R61H104KE14%23"
			(at 160.02 100.33 0)
			(effects
				(font
					(size 1.27 1.27)
					(thickness 0.15)
				)
				(justify left bottom)
				(hide yes)
			)
		)
		(property "Description" "SMD Multilayer Ceramic Capacitor, 0.1 µF, 50 V, 0402 [1005 Metric], ± 10%, X5R, GRM Series"
			(at 175.26 120.65 0)
			(effects
				(font
					(size 1.27 1.27)
				)
				(hide yes)
			)
		)
		(property "MPN" "GRM155R61H104KE14D"
			(at 157.48 100.33 0)
			(effects
				(font
					(size 1.27 1.27)
					(thickness 0.15)
				)
				(justify left bottom)
				(hide yes)
			)
		)
		(property "Manufacturer" "Murata"
			(at 154.94 100.33 0)
			(effects
				(font
					(size 1.27 1.27)
					(thickness 0.15)
				)
				(justify left bottom)
				(hide yes)
			)
		)
		(property "License" "Apache-2.0"
			(at 152.4 100.33 0)
			(effects
				(font
					(size 1.27 1.27)
					(thickness 0.15)
				)
				(justify left bottom)
				(hide yes)
			)
		)
		(property "Author" "Antmicro"
			(at 149.86 100.33 0)
			(effects
				(font
					(size 1.27 1.27)
					(thickness 0.15)
				)
				(justify left bottom)
				(hide yes)
			)
		)
		(property "Val" "100n"
			(at 173.355 119.38 90)
			(effects
				(font
					(size 1.27 1.27)
					(thickness 0.15)
				)
				(justify right)
			)
		)
		(property "Voltage" "50V"
			(at 147.32 100.33 0)
			(effects
				(font
					(size 1.27 1.27)
				)
				(justify left bottom)
				(hide yes)
			)
		)
		(property "Dielectric" "X5R"
			(at 144.78 100.33 0)
			(effects
				(font
					(size 1.27 1.27)
				)
				(justify left bottom)
				(hide yes)
			)
		)
		(pin "1"
		)
		(pin "2"
		)
		(instances
			(project "gmsl-deserializer"
				(path ""
					(reference "C31")
					(unit 1)
				)
			)
		)
	)
	(symbol
		(lib_id "antmicropower:+1V8")
		(at 132.08 111.76 0)
		(mirror y)
		(unit 1)
		(exclude_from_sim no)
		(in_bom yes)
		(on_board yes)
		(dnp no)
		(property "Reference" "#PWR02"
			(at 116.84 114.3 0)
			(effects
				(font
					(size 1.27 1.27)
					(thickness 0.15)
				)
				(justify left bottom)
				(hide yes)
			)
		)
		(property "Value" "+1V8"
			(at 132.08 107.95 0)
			(effects
				(font
					(size 1.27 1.27)
					(thickness 0.15)
				)
			)
		)
		(property "Footprint" ""
			(at 116.84 119.38 0)
			(effects
				(font
					(size 1.27 1.27)
					(thickness 0.15)
				)
				(justify left bottom)
				(hide yes)
			)
		)
		(property "Datasheet" ""
			(at 116.84 121.92 0)
			(effects
				(font
					(size 1.27 1.27)
					(thickness 0.15)
				)
				(justify left bottom)
				(hide yes)
			)
		)
		(property "Description" ""
			(at 132.08 111.76 0)
			(effects
				(font
					(size 1.27 1.27)
				)
				(hide yes)
			)
		)
		(property "Author" "Antmicro"
			(at 116.84 119.38 0)
			(effects
				(font
					(size 1.27 1.27)
					(thickness 0.15)
				)
				(justify left bottom)
				(hide yes)
			)
		)
		(property "License" "Apache-2.0"
			(at 116.84 121.92 0)
			(effects
				(font
					(size 1.27 1.27)
					(thickness 0.15)
				)
				(justify left bottom)
				(hide yes)
			)
		)
		(pin "1"
		)
		(instances
			(project "gmsl-deserializer"
				(path ""
					(reference "#PWR02")
					(unit 1)
				)
			)
		)
	)
	(symbol
		(lib_id "antmicroCapacitors0402:C_100n_0402")
		(at 132.08 119.38 90)
		(unit 1)
		(exclude_from_sim no)
		(in_bom yes)
		(on_board yes)
		(dnp no)
		(property "Reference" "C26"
			(at 133.985 115.57 90)
			(effects
				(font
					(size 1.27 1.27)
					(thickness 0.15)
				)
				(justify right)
			)
		)
		(property "Value" "C_100n_0402"
			(at 142.24 99.06 0)
			(effects
				(font
					(size 1.27 1.27)
					(thickness 0.15)
				)
				(justify left bottom)
				(hide yes)
			)
		)
		(property "Footprint" "antmicro-footprints:C_0402_1005Metric"
			(at 144.78 99.06 0)
			(effects
				(font
					(size 1.27 1.27)
					(thickness 0.15)
				)
				(justify left bottom)
				(hide yes)
			)
		)
		(property "Datasheet" "https://www.murata.com/products/productdetail?partno=GRM155R61H104KE14%23"
			(at 147.32 99.06 0)
			(effects
				(font
					(size 1.27 1.27)
					(thickness 0.15)
				)
				(justify left bottom)
				(hide yes)
			)
		)
		(property "Description" "SMD Multilayer Ceramic Capacitor, 0.1 µF, 50 V, 0402 [1005 Metric], ± 10%, X5R, GRM Series"
			(at 132.08 119.38 0)
			(effects
				(font
					(size 1.27 1.27)
				)
				(hide yes)
			)
		)
		(property "MPN" "GRM155R61H104KE14D"
			(at 149.86 99.06 0)
			(effects
				(font
					(size 1.27 1.27)
					(thickness 0.15)
				)
				(justify left bottom)
				(hide yes)
			)
		)
		(property "Manufacturer" "Murata"
			(at 152.4 99.06 0)
			(effects
				(font
					(size 1.27 1.27)
					(thickness 0.15)
				)
				(justify left bottom)
				(hide yes)
			)
		)
		(property "License" "Apache-2.0"
			(at 154.94 99.06 0)
			(effects
				(font
					(size 1.27 1.27)
					(thickness 0.15)
				)
				(justify left bottom)
				(hide yes)
			)
		)
		(property "Author" "Antmicro"
			(at 157.48 99.06 0)
			(effects
				(font
					(size 1.27 1.27)
					(thickness 0.15)
				)
				(justify left bottom)
				(hide yes)
			)
		)
		(property "Val" "100n"
			(at 133.985 118.11 90)
			(effects
				(font
					(size 1.27 1.27)
					(thickness 0.15)
				)
				(justify right)
			)
		)
		(property "Voltage" "50V"
			(at 160.02 99.06 0)
			(effects
				(font
					(size 1.27 1.27)
				)
				(justify left bottom)
				(hide yes)
			)
		)
		(property "Dielectric" "X5R"
			(at 162.56 99.06 0)
			(effects
				(font
					(size 1.27 1.27)
				)
				(justify left bottom)
				(hide yes)
			)
		)
		(pin "1"
		)
		(pin "2"
		)
		(instances
			(project "gmsl-deserializer"
				(path ""
					(reference "C26")
					(unit 1)
				)
			)
		)
	)
	(symbol
		(lib_id "antmicroResistors0402:R_470R_0402")
		(at 41.91 228.6 90)
		(unit 1)
		(exclude_from_sim no)
		(in_bom yes)
		(on_board yes)
		(dnp no)
		(fields_autoplaced yes)
		(property "Reference" "R82"
			(at 44.45 224.7899 90)
			(effects
				(font
					(size 1.27 1.27)
					(thickness 0.15)
				)
				(justify right)
			)
		)
		(property "Value" "R_470R_0402"
			(at 54.61 208.28 0)
			(effects
				(font
					(size 1.27 1.27)
					(thickness 0.15)
				)
				(justify left bottom)
				(hide yes)
			)
		)
		(property "Footprint" "antmicro-footprints:R_0402_1005Metric"
			(at 57.15 208.28 0)
			(effects
				(font
					(size 1.27 1.27)
					(thickness 0.15)
				)
				(justify left bottom)
				(hide yes)
			)
		)
		(property "Datasheet" "https://www.bourns.com/docs/product-datasheets/cr.pdf"
			(at 59.69 208.28 0)
			(effects
				(font
					(size 1.27 1.27)
					(thickness 0.15)
				)
				(justify left bottom)
				(hide yes)
			)
		)
		(property "Description" "SMD Chip Resistor, 470 ohm, ± 1%, 62.5 mW, 0402 [1005 Metric], Thick Film, General Purpose"
			(at 41.91 228.6 0)
			(effects
				(font
					(size 1.27 1.27)
				)
				(hide yes)
			)
		)
		(property "MPN" "CR0402-FX-4700GLF"
			(at 62.23 208.28 0)
			(effects
				(font
					(size 1.27 1.27)
					(thickness 0.15)
				)
				(justify left bottom)
				(hide yes)
			)
		)
		(property "Manufacturer" "Bourns"
			(at 64.77 208.28 0)
			(effects
				(font
					(size 1.27 1.27)
					(thickness 0.15)
				)
				(justify left bottom)
				(hide yes)
			)
		)
		(property "License" "Apache-2.0"
			(at 67.31 208.28 0)
			(effects
				(font
					(size 1.27 1.27)
					(thickness 0.15)
				)
				(justify left bottom)
				(hide yes)
			)
		)
		(property "Author" "Antmicro"
			(at 69.85 208.28 0)
			(effects
				(font
					(size 1.27 1.27)
					(thickness 0.15)
				)
				(justify left bottom)
				(hide yes)
			)
		)
		(property "Val" "470R"
			(at 44.45 227.3299 90)
			(effects
				(font
					(size 1.27 1.27)
					(thickness 0.15)
				)
				(justify right)
			)
		)
		(property "Tolerance" "1%"
			(at 52.07 208.28 0)
			(effects
				(font
					(size 1.27 1.27)
				)
				(justify left bottom)
				(hide yes)
			)
		)
		(pin "1"
		)
		(pin "2"
		)
		(instances
			(project "gmsl-deserializer"
				(path ""
					(reference "R82")
					(unit 1)
				)
			)
		)
	)
	(symbol
		(lib_id "antmicroCoaxialConnectorsRF:Conn_FAKRA_7-2287906-0")
		(at 153.67 210.82 0)
		(unit 1)
		(exclude_from_sim no)
		(in_bom yes)
		(on_board yes)
		(dnp no)
		(fields_autoplaced yes)
		(property "Reference" "J3"
			(at 162.56 209.9067 0)
			(effects
				(font
					(size 1.27 1.27)
					(thickness 0.15)
				)
				(justify left)
			)
		)
		(property "Value" "Conn_FAKRA_59S2AQ-40MT5-Z_1"
			(at 173.99 218.44 0)
			(effects
				(font
					(size 1.27 1.27)
					(thickness 0.15)
				)
				(justify left bottom)
				(hide yes)
			)
		)
		(property "Footprint" "antmicro-footprints:Conn_FAKRA_7-2287906-0"
			(at 173.99 220.98 0)
			(effects
				(font
					(size 1.27 1.27)
					(thickness 0.15)
				)
				(justify left bottom)
				(hide yes)
			)
		)
		(property "Datasheet" "https://www.te.com/en/product-7-2287906-0.html"
			(at 173.99 223.52 0)
			(effects
				(font
					(size 1.27 1.27)
					(thickness 0.15)
				)
				(justify left bottom)
				(hide yes)
			)
		)
		(property "Description" "FAKRA, 1 POS, ASSY EDGE MOUNT, 12OCLOCK"
			(at 153.67 210.82 0)
			(effects
				(font
					(size 1.27 1.27)
				)
				(hide yes)
			)
		)
		(property "MPN" "7-2287906-0"
			(at 162.56 212.4467 0)
			(effects
				(font
					(size 1.27 1.27)
					(thickness 0.15)
				)
				(justify left)
			)
		)
		(property "Manufacturer" "TE Connectivity"
			(at 173.99 228.6 0)
			(effects
				(font
					(size 1.27 1.27)
					(thickness 0.15)
				)
				(justify left bottom)
				(hide yes)
			)
		)
		(property "Author" "Antmicro"
			(at 173.99 231.14 0)
			(effects
				(font
					(size 1.27 1.27)
					(thickness 0.15)
				)
				(justify left bottom)
				(hide yes)
			)
		)
		(property "License" "Apache-2.0"
			(at 173.99 233.68 0)
			(effects
				(font
					(size 1.27 1.27)
					(thickness 0.15)
				)
				(justify left bottom)
				(hide yes)
			)
		)
		(pin "1"
		)
		(pin "2"
		)
		(pin "3"
		)
		(pin "4"
		)
		(pin "5"
		)
		(instances
			(project "gmsl-deserializer"
				(path ""
					(reference "J3")
					(unit 1)
				)
			)
		)
	)
	(symbol
		(lib_id "antmicropower:GND")
		(at 259.08 224.79 0)
		(unit 1)
		(exclude_from_sim no)
		(in_bom yes)
		(on_board yes)
		(dnp no)
		(property "Reference" "#PWR060"
			(at 267.97 227.33 0)
			(effects
				(font
					(size 1.27 1.27)
					(thickness 0.15)
				)
				(justify left bottom)
				(hide yes)
			)
		)
		(property "Value" "GND"
			(at 259.08 228.6 0)
			(effects
				(font
					(size 1.27 1.27)
					(thickness 0.15)
				)
			)
		)
		(property "Footprint" ""
			(at 267.97 232.41 0)
			(effects
				(font
					(size 1.27 1.27)
					(thickness 0.15)
				)
				(justify left bottom)
				(hide yes)
			)
		)
		(property "Datasheet" ""
			(at 267.97 237.49 0)
			(effects
				(font
					(size 1.27 1.27)
					(thickness 0.15)
				)
				(justify left bottom)
				(hide yes)
			)
		)
		(property "Description" ""
			(at 259.08 224.79 0)
			(effects
				(font
					(size 1.27 1.27)
				)
				(hide yes)
			)
		)
		(property "Author" "Antmicro"
			(at 267.97 232.41 0)
			(effects
				(font
					(size 1.27 1.27)
					(thickness 0.15)
				)
				(justify left bottom)
				(hide yes)
			)
		)
		(property "License" "Apache-2.0"
			(at 267.97 234.95 0)
			(effects
				(font
					(size 1.27 1.27)
					(thickness 0.15)
				)
				(justify left bottom)
				(hide yes)
			)
		)
		(pin "1"
		)
		(instances
			(project "gmsl-deserializer"
				(path ""
					(reference "#PWR060")
					(unit 1)
				)
			)
		)
	)
	(symbol
		(lib_id "antmicropower:GND")
		(at 166.37 138.43 0)
		(unit 1)
		(exclude_from_sim no)
		(in_bom yes)
		(on_board yes)
		(dnp no)
		(property "Reference" "#PWR04"
			(at 175.26 140.97 0)
			(effects
				(font
					(size 1.27 1.27)
					(thickness 0.15)
				)
				(justify left bottom)
				(hide yes)
			)
		)
		(property "Value" "GND"
			(at 166.37 142.24 0)
			(effects
				(font
					(size 1.27 1.27)
					(thickness 0.15)
				)
			)
		)
		(property "Footprint" ""
			(at 175.26 146.05 0)
			(effects
				(font
					(size 1.27 1.27)
					(thickness 0.15)
				)
				(justify left bottom)
				(hide yes)
			)
		)
		(property "Datasheet" ""
			(at 175.26 151.13 0)
			(effects
				(font
					(size 1.27 1.27)
					(thickness 0.15)
				)
				(justify left bottom)
				(hide yes)
			)
		)
		(property "Description" ""
			(at 166.37 138.43 0)
			(effects
				(font
					(size 1.27 1.27)
				)
				(hide yes)
			)
		)
		(property "Author" "Antmicro"
			(at 175.26 146.05 0)
			(effects
				(font
					(size 1.27 1.27)
					(thickness 0.15)
				)
				(justify left bottom)
				(hide yes)
			)
		)
		(property "License" "Apache-2.0"
			(at 175.26 148.59 0)
			(effects
				(font
					(size 1.27 1.27)
					(thickness 0.15)
				)
				(justify left bottom)
				(hide yes)
			)
		)
		(pin "1"
		)
		(instances
			(project "gmsl-deserializer"
				(path ""
					(reference "#PWR04")
					(unit 1)
				)
			)
		)
	)
	(symbol
		(lib_id "antmicroCapacitors0402:C_100n_0402")
		(at 146.05 62.23 90)
		(unit 1)
		(exclude_from_sim no)
		(in_bom yes)
		(on_board yes)
		(dnp no)
		(property "Reference" "C3"
			(at 147.955 58.42 90)
			(effects
				(font
					(size 1.27 1.27)
					(thickness 0.15)
				)
				(justify right)
			)
		)
		(property "Value" "C_100n_0402"
			(at 156.21 41.91 0)
			(effects
				(font
					(size 1.27 1.27)
					(thickness 0.15)
				)
				(justify left bottom)
				(hide yes)
			)
		)
		(property "Footprint" "antmicro-footprints:C_0402_1005Metric"
			(at 158.75 41.91 0)
			(effects
				(font
					(size 1.27 1.27)
					(thickness 0.15)
				)
				(justify left bottom)
				(hide yes)
			)
		)
		(property "Datasheet" "https://www.murata.com/products/productdetail?partno=GRM155R61H104KE14%23"
			(at 161.29 41.91 0)
			(effects
				(font
					(size 1.27 1.27)
					(thickness 0.15)
				)
				(justify left bottom)
				(hide yes)
			)
		)
		(property "Description" "SMD Multilayer Ceramic Capacitor, 0.1 µF, 50 V, 0402 [1005 Metric], ± 10%, X5R, GRM Series"
			(at 146.05 62.23 0)
			(effects
				(font
					(size 1.27 1.27)
				)
				(hide yes)
			)
		)
		(property "MPN" "GRM155R61H104KE14D"
			(at 163.83 41.91 0)
			(effects
				(font
					(size 1.27 1.27)
					(thickness 0.15)
				)
				(justify left bottom)
				(hide yes)
			)
		)
		(property "Manufacturer" "Murata"
			(at 166.37 41.91 0)
			(effects
				(font
					(size 1.27 1.27)
					(thickness 0.15)
				)
				(justify left bottom)
				(hide yes)
			)
		)
		(property "License" "Apache-2.0"
			(at 168.91 41.91 0)
			(effects
				(font
					(size 1.27 1.27)
					(thickness 0.15)
				)
				(justify left bottom)
				(hide yes)
			)
		)
		(property "Author" "Antmicro"
			(at 171.45 41.91 0)
			(effects
				(font
					(size 1.27 1.27)
					(thickness 0.15)
				)
				(justify left bottom)
				(hide yes)
			)
		)
		(property "Val" "100n"
			(at 147.955 60.96 90)
			(effects
				(font
					(size 1.27 1.27)
					(thickness 0.15)
				)
				(justify right)
			)
		)
		(property "Voltage" "50V"
			(at 173.99 41.91 0)
			(effects
				(font
					(size 1.27 1.27)
				)
				(justify left bottom)
				(hide yes)
			)
		)
		(property "Dielectric" "X5R"
			(at 176.53 41.91 0)
			(effects
				(font
					(size 1.27 1.27)
				)
				(justify left bottom)
				(hide yes)
			)
		)
		(pin "1"
		)
		(pin "2"
		)
		(instances
			(project "gmsl-deserializer"
				(path ""
					(reference "C3")
					(unit 1)
				)
			)
		)
	)
	(symbol
		(lib_id "antmicropower:GND")
		(at 158.75 264.16 0)
		(unit 1)
		(exclude_from_sim no)
		(in_bom yes)
		(on_board yes)
		(dnp no)
		(property "Reference" "#PWR0107"
			(at 167.64 266.7 0)
			(effects
				(font
					(size 1.27 1.27)
					(thickness 0.15)
				)
				(justify left bottom)
				(hide yes)
			)
		)
		(property "Value" "GND"
			(at 158.75 267.97 0)
			(effects
				(font
					(size 1.27 1.27)
					(thickness 0.15)
				)
			)
		)
		(property "Footprint" ""
			(at 167.64 271.78 0)
			(effects
				(font
					(size 1.27 1.27)
					(thickness 0.15)
				)
				(justify left bottom)
				(hide yes)
			)
		)
		(property "Datasheet" ""
			(at 167.64 276.86 0)
			(effects
				(font
					(size 1.27 1.27)
					(thickness 0.15)
				)
				(justify left bottom)
				(hide yes)
			)
		)
		(property "Description" ""
			(at 158.75 264.16 0)
			(effects
				(font
					(size 1.27 1.27)
				)
				(hide yes)
			)
		)
		(property "Author" "Antmicro"
			(at 167.64 271.78 0)
			(effects
				(font
					(size 1.27 1.27)
					(thickness 0.15)
				)
				(justify left bottom)
				(hide yes)
			)
		)
		(property "License" "Apache-2.0"
			(at 167.64 274.32 0)
			(effects
				(font
					(size 1.27 1.27)
					(thickness 0.15)
				)
				(justify left bottom)
				(hide yes)
			)
		)
		(pin "1"
		)
		(instances
			(project "gmsl-deserializer"
				(path ""
					(reference "#PWR0107")
					(unit 1)
				)
			)
		)
	)
	(symbol
		(lib_id "antmicropower:+1V8")
		(at 120.65 123.19 0)
		(mirror y)
		(unit 1)
		(exclude_from_sim no)
		(in_bom yes)
		(on_board yes)
		(dnp no)
		(property "Reference" "#PWR01"
			(at 105.41 125.73 0)
			(effects
				(font
					(size 1.27 1.27)
					(thickness 0.15)
				)
				(justify left bottom)
				(hide yes)
			)
		)
		(property "Value" "+1V8"
			(at 120.65 119.38 0)
			(effects
				(font
					(size 1.27 1.27)
					(thickness 0.15)
				)
			)
		)
		(property "Footprint" ""
			(at 105.41 130.81 0)
			(effects
				(font
					(size 1.27 1.27)
					(thickness 0.15)
				)
				(justify left bottom)
				(hide yes)
			)
		)
		(property "Datasheet" ""
			(at 105.41 133.35 0)
			(effects
				(font
					(size 1.27 1.27)
					(thickness 0.15)
				)
				(justify left bottom)
				(hide yes)
			)
		)
		(property "Description" ""
			(at 120.65 123.19 0)
			(effects
				(font
					(size 1.27 1.27)
				)
				(hide yes)
			)
		)
		(property "Author" "Antmicro"
			(at 105.41 130.81 0)
			(effects
				(font
					(size 1.27 1.27)
					(thickness 0.15)
				)
				(justify left bottom)
				(hide yes)
			)
		)
		(property "License" "Apache-2.0"
			(at 105.41 133.35 0)
			(effects
				(font
					(size 1.27 1.27)
					(thickness 0.15)
				)
				(justify left bottom)
				(hide yes)
			)
		)
		(pin "1"
		)
		(instances
			(project "gmsl-deserializer"
				(path ""
					(reference "#PWR01")
					(unit 1)
				)
			)
		)
	)
	(symbol
		(lib_id "antmicropower:+1V8")
		(at 200.66 55.88 0)
		(unit 1)
		(exclude_from_sim no)
		(in_bom yes)
		(on_board yes)
		(dnp no)
		(property "Reference" "#PWR015"
			(at 215.9 58.42 0)
			(effects
				(font
					(size 1.27 1.27)
					(thickness 0.15)
				)
				(justify left bottom)
				(hide yes)
			)
		)
		(property "Value" "+1V8"
			(at 200.66 52.07 0)
			(effects
				(font
					(size 1.27 1.27)
					(thickness 0.15)
				)
			)
		)
		(property "Footprint" ""
			(at 215.9 63.5 0)
			(effects
				(font
					(size 1.27 1.27)
					(thickness 0.15)
				)
				(justify left bottom)
				(hide yes)
			)
		)
		(property "Datasheet" ""
			(at 215.9 66.04 0)
			(effects
				(font
					(size 1.27 1.27)
					(thickness 0.15)
				)
				(justify left bottom)
				(hide yes)
			)
		)
		(property "Description" ""
			(at 200.66 55.88 0)
			(effects
				(font
					(size 1.27 1.27)
				)
				(hide yes)
			)
		)
		(property "Author" "Antmicro"
			(at 215.9 63.5 0)
			(effects
				(font
					(size 1.27 1.27)
					(thickness 0.15)
				)
				(justify left bottom)
				(hide yes)
			)
		)
		(property "License" "Apache-2.0"
			(at 215.9 66.04 0)
			(effects
				(font
					(size 1.27 1.27)
					(thickness 0.15)
				)
				(justify left bottom)
				(hide yes)
			)
		)
		(pin "1"
		)
		(instances
			(project "gmsl-deserializer"
				(path ""
					(reference "#PWR015")
					(unit 1)
				)
			)
		)
	)
	(symbol
		(lib_id "antmicroTVSDiodes:ESD5B5_0ST1G")
		(at 306.07 207.01 90)
		(unit 1)
		(exclude_from_sim no)
		(in_bom yes)
		(on_board yes)
		(dnp no)
		(property "Reference" "D9"
			(at 304.165 203.2 90)
			(effects
				(font
					(size 1.27 1.27)
					(thickness 0.15)
				)
				(justify left)
			)
		)
		(property "Value" "ESD5B5_0ST1G"
			(at 289.56 205.74 90)
			(effects
				(font
					(size 1.27 1.27)
					(thickness 0.15)
				)
				(justify right)
			)
		)
		(property "Footprint" "antmicro-footprints:SOD-523_NP"
			(at 316.23 181.61 0)
			(effects
				(font
					(size 1.27 1.27)
					(thickness 0.15)
				)
				(justify left bottom)
				(hide yes)
			)
		)
		(property "Datasheet" "https://www.onsemi.com/pdf/datasheet/esd5b5.0st1-d.pdf"
			(at 318.77 181.61 0)
			(effects
				(font
					(size 1.27 1.27)
					(thickness 0.15)
				)
				(justify left bottom)
				(hide yes)
			)
		)
		(property "Description" "Bidirectional TVS, 30 kV,  SOD-523, 5 V, 32 pF"
			(at 306.07 207.01 0)
			(effects
				(font
					(size 1.27 1.27)
				)
				(hide yes)
			)
		)
		(property "Manufacturer" "ON Semiconductor"
			(at 321.31 181.61 0)
			(effects
				(font
					(size 1.27 1.27)
					(thickness 0.15)
				)
				(justify left bottom)
				(hide yes)
			)
		)
		(property "MPN" "ESD5B5.0ST1G"
			(at 323.85 181.61 0)
			(effects
				(font
					(size 1.27 1.27)
					(thickness 0.15)
				)
				(justify left bottom)
				(hide yes)
			)
		)
		(property "Author" "Antmicro"
			(at 326.39 181.61 0)
			(effects
				(font
					(size 1.27 1.27)
					(thickness 0.15)
				)
				(justify left bottom)
				(hide yes)
			)
		)
		(property "License" "Apache-2.0"
			(at 328.93 181.61 0)
			(effects
				(font
					(size 1.27 1.27)
					(thickness 0.15)
				)
				(justify left bottom)
				(hide yes)
			)
		)
		(pin "1"
		)
		(pin "2"
		)
		(instances
			(project "gmsl-deserializer"
				(path ""
					(reference "D9")
					(unit 1)
				)
			)
		)
	)
	(symbol
		(lib_id "antmicropower:GND")
		(at 284.48 170.18 0)
		(unit 1)
		(exclude_from_sim no)
		(in_bom yes)
		(on_board yes)
		(dnp no)
		(property "Reference" "#PWR08"
			(at 293.37 172.72 0)
			(effects
				(font
					(size 1.27 1.27)
					(thickness 0.15)
				)
				(justify left bottom)
				(hide yes)
			)
		)
		(property "Value" "GND"
			(at 284.48 173.99 0)
			(effects
				(font
					(size 1.27 1.27)
					(thickness 0.15)
				)
			)
		)
		(property "Footprint" ""
			(at 293.37 177.8 0)
			(effects
				(font
					(size 1.27 1.27)
					(thickness 0.15)
				)
				(justify left bottom)
				(hide yes)
			)
		)
		(property "Datasheet" ""
			(at 293.37 182.88 0)
			(effects
				(font
					(size 1.27 1.27)
					(thickness 0.15)
				)
				(justify left bottom)
				(hide yes)
			)
		)
		(property "Description" ""
			(at 284.48 170.18 0)
			(effects
				(font
					(size 1.27 1.27)
				)
				(hide yes)
			)
		)
		(property "Author" "Antmicro"
			(at 293.37 177.8 0)
			(effects
				(font
					(size 1.27 1.27)
					(thickness 0.15)
				)
				(justify left bottom)
				(hide yes)
			)
		)
		(property "License" "Apache-2.0"
			(at 293.37 180.34 0)
			(effects
				(font
					(size 1.27 1.27)
					(thickness 0.15)
				)
				(justify left bottom)
				(hide yes)
			)
		)
		(pin "1"
		)
		(instances
			(project "gmsl-deserializer"
				(path ""
					(reference "#PWR08")
					(unit 1)
				)
			)
		)
	)
	(symbol
		(lib_id "antmicroTestPoints:TP_0.75mm_SMD")
		(at 97.79 130.81 90)
		(unit 1)
		(exclude_from_sim no)
		(in_bom yes)
		(on_board yes)
		(dnp no)
		(property "Reference" "TP24"
			(at 96.52 125.73 90)
			(effects
				(font
					(size 1.27 1.27)
					(thickness 0.15)
				)
				(justify right)
			)
		)
		(property "Value" "TP_0.75mm_SMD"
			(at 101.6 120.015 0)
			(effects
				(font
					(size 1.27 1.27)
					(thickness 0.15)
				)
				(justify left bottom)
				(hide yes)
			)
		)
		(property "Footprint" "antmicro-footprints:TP_SMD_0.75mm"
			(at 104.14 120.015 0)
			(effects
				(font
					(size 1.27 1.27)
					(thickness 0.15)
				)
				(justify left bottom)
				(hide yes)
			)
		)
		(property "Datasheet" ""
			(at 110.49 113.03 0)
			(effects
				(font
					(size 1.27 1.27)
					(thickness 0.15)
				)
				(justify left bottom)
				(hide yes)
			)
		)
		(property "Description" "SMT test point"
			(at 97.79 130.81 0)
			(effects
				(font
					(size 1.27 1.27)
				)
				(hide yes)
			)
		)
		(property "MPN" ""
			(at 109.22 120.015 0)
			(effects
				(font
					(size 1.27 1.27)
					(thickness 0.15)
				)
				(justify left bottom)
				(hide yes)
			)
		)
		(property "Manufacturer" ""
			(at 104.14 120.015 0)
			(effects
				(font
					(size 1.27 1.27)
					(thickness 0.15)
				)
				(justify left bottom)
				(hide yes)
			)
		)
		(property "Author" "Antmicro"
			(at 106.68 120.015 0)
			(effects
				(font
					(size 1.27 1.27)
					(thickness 0.15)
				)
				(justify left bottom)
				(hide yes)
			)
		)
		(property "License" "Apache-2.0"
			(at 109.22 120.015 0)
			(effects
				(font
					(size 1.27 1.27)
					(thickness 0.15)
				)
				(justify left bottom)
				(hide yes)
			)
		)
		(pin "1"
		)
		(instances
			(project "gmsl-deserializer"
				(path ""
					(reference "TP24")
					(unit 1)
				)
			)
		)
	)
	(symbol
		(lib_id "antmicropower:GND")
		(at 158.75 240.03 0)
		(unit 1)
		(exclude_from_sim no)
		(in_bom yes)
		(on_board yes)
		(dnp no)
		(property "Reference" "#PWR0106"
			(at 167.64 242.57 0)
			(effects
				(font
					(size 1.27 1.27)
					(thickness 0.15)
				)
				(justify left bottom)
				(hide yes)
			)
		)
		(property "Value" "GND"
			(at 158.75 243.84 0)
			(effects
				(font
					(size 1.27 1.27)
					(thickness 0.15)
				)
			)
		)
		(property "Footprint" ""
			(at 167.64 247.65 0)
			(effects
				(font
					(size 1.27 1.27)
					(thickness 0.15)
				)
				(justify left bottom)
				(hide yes)
			)
		)
		(property "Datasheet" ""
			(at 167.64 252.73 0)
			(effects
				(font
					(size 1.27 1.27)
					(thickness 0.15)
				)
				(justify left bottom)
				(hide yes)
			)
		)
		(property "Description" ""
			(at 158.75 240.03 0)
			(effects
				(font
					(size 1.27 1.27)
				)
				(hide yes)
			)
		)
		(property "Author" "Antmicro"
			(at 167.64 247.65 0)
			(effects
				(font
					(size 1.27 1.27)
					(thickness 0.15)
				)
				(justify left bottom)
				(hide yes)
			)
		)
		(property "License" "Apache-2.0"
			(at 167.64 250.19 0)
			(effects
				(font
					(size 1.27 1.27)
					(thickness 0.15)
				)
				(justify left bottom)
				(hide yes)
			)
		)
		(pin "1"
		)
		(instances
			(project "gmsl-deserializer"
				(path ""
					(reference "#PWR0106")
					(unit 1)
				)
			)
		)
	)
	(symbol
		(lib_id "antmicropower:GND")
		(at 306.07 208.28 0)
		(unit 1)
		(exclude_from_sim no)
		(in_bom yes)
		(on_board yes)
		(dnp no)
		(property "Reference" "#PWR0115"
			(at 314.96 210.82 0)
			(effects
				(font
					(size 1.27 1.27)
					(thickness 0.15)
				)
				(justify left bottom)
				(hide yes)
			)
		)
		(property "Value" "GND"
			(at 306.07 212.09 0)
			(effects
				(font
					(size 1.27 1.27)
					(thickness 0.15)
				)
			)
		)
		(property "Footprint" ""
			(at 314.96 215.9 0)
			(effects
				(font
					(size 1.27 1.27)
					(thickness 0.15)
				)
				(justify left bottom)
				(hide yes)
			)
		)
		(property "Datasheet" ""
			(at 314.96 220.98 0)
			(effects
				(font
					(size 1.27 1.27)
					(thickness 0.15)
				)
				(justify left bottom)
				(hide yes)
			)
		)
		(property "Description" ""
			(at 306.07 208.28 0)
			(effects
				(font
					(size 1.27 1.27)
				)
				(hide yes)
			)
		)
		(property "Author" "Antmicro"
			(at 314.96 215.9 0)
			(effects
				(font
					(size 1.27 1.27)
					(thickness 0.15)
				)
				(justify left bottom)
				(hide yes)
			)
		)
		(property "License" "Apache-2.0"
			(at 314.96 218.44 0)
			(effects
				(font
					(size 1.27 1.27)
					(thickness 0.15)
				)
				(justify left bottom)
				(hide yes)
			)
		)
		(pin "1"
		)
		(instances
			(project "gmsl-deserializer"
				(path ""
					(reference "#PWR0115")
					(unit 1)
				)
			)
		)
	)
	(symbol
		(lib_id "antmicroTVSDiodes:ESD5B5_0ST1G")
		(at 308.61 185.42 90)
		(unit 1)
		(exclude_from_sim no)
		(in_bom yes)
		(on_board yes)
		(dnp no)
		(property "Reference" "D10"
			(at 309.88 181.61 90)
			(effects
				(font
					(size 1.27 1.27)
					(thickness 0.15)
				)
				(justify right)
			)
		)
		(property "Value" "ESD5B5_0ST1G"
			(at 309.88 184.15 90)
			(effects
				(font
					(size 1.27 1.27)
					(thickness 0.15)
				)
				(justify right)
			)
		)
		(property "Footprint" "antmicro-footprints:SOD-523_NP"
			(at 318.77 160.02 0)
			(effects
				(font
					(size 1.27 1.27)
					(thickness 0.15)
				)
				(justify left bottom)
				(hide yes)
			)
		)
		(property "Datasheet" "https://www.onsemi.com/pdf/datasheet/esd5b5.0st1-d.pdf"
			(at 321.31 160.02 0)
			(effects
				(font
					(size 1.27 1.27)
					(thickness 0.15)
				)
				(justify left bottom)
				(hide yes)
			)
		)
		(property "Description" "Bidirectional TVS, 30 kV,  SOD-523, 5 V, 32 pF"
			(at 308.61 185.42 0)
			(effects
				(font
					(size 1.27 1.27)
				)
				(hide yes)
			)
		)
		(property "Manufacturer" "ON Semiconductor"
			(at 323.85 160.02 0)
			(effects
				(font
					(size 1.27 1.27)
					(thickness 0.15)
				)
				(justify left bottom)
				(hide yes)
			)
		)
		(property "MPN" "ESD5B5.0ST1G"
			(at 326.39 160.02 0)
			(effects
				(font
					(size 1.27 1.27)
					(thickness 0.15)
				)
				(justify left bottom)
				(hide yes)
			)
		)
		(property "Author" "Antmicro"
			(at 328.93 160.02 0)
			(effects
				(font
					(size 1.27 1.27)
					(thickness 0.15)
				)
				(justify left bottom)
				(hide yes)
			)
		)
		(property "License" "Apache-2.0"
			(at 331.47 160.02 0)
			(effects
				(font
					(size 1.27 1.27)
					(thickness 0.15)
				)
				(justify left bottom)
				(hide yes)
			)
		)
		(pin "1"
		)
		(pin "2"
		)
		(instances
			(project "gmsl-deserializer"
				(path ""
					(reference "D10")
					(unit 1)
				)
			)
		)
	)
	(symbol
		(lib_id "antmicroResistors0402:R_0R_0402")
		(at 203.2 72.39 0)
		(mirror y)
		(unit 1)
		(exclude_from_sim no)
		(in_bom yes)
		(on_board yes)
		(dnp no)
		(property "Reference" "R5"
			(at 196.85 71.12 0)
			(effects
				(font
					(size 1.27 1.27)
					(thickness 0.15)
				)
			)
		)
		(property "Value" "R_0R_0402"
			(at 182.88 85.09 0)
			(effects
				(font
					(size 1.27 1.27)
					(thickness 0.15)
				)
				(justify left bottom)
				(hide yes)
			)
		)
		(property "Footprint" "antmicro-footprints:R_0402_1005Metric"
			(at 182.88 87.63 0)
			(effects
				(font
					(size 1.27 1.27)
					(thickness 0.15)
				)
				(justify left bottom)
				(hide yes)
			)
		)
		(property "Datasheet" "https://industrial.panasonic.com/cdbs/www-data/pdf/RDA0000/AOA0000C301.pdf"
			(at 182.88 90.17 0)
			(effects
				(font
					(size 1.27 1.27)
					(thickness 0.15)
				)
				(justify left bottom)
				(hide yes)
			)
		)
		(property "Description" "SMD Chip Resistor, Jumper, 0 ohm, 100 mW, 0402 [1005 Metric], Thick Film, General Purpose"
			(at 203.2 72.39 0)
			(effects
				(font
					(size 1.27 1.27)
				)
				(hide yes)
			)
		)
		(property "MPN" "ERJ2GE0R00X"
			(at 182.88 92.71 0)
			(effects
				(font
					(size 1.27 1.27)
					(thickness 0.15)
				)
				(justify left bottom)
				(hide yes)
			)
		)
		(property "Manufacturer" "Panasonic"
			(at 182.88 95.25 0)
			(effects
				(font
					(size 1.27 1.27)
					(thickness 0.15)
				)
				(justify left bottom)
				(hide yes)
			)
		)
		(property "License" "Apache-2.0"
			(at 182.88 97.79 0)
			(effects
				(font
					(size 1.27 1.27)
					(thickness 0.15)
				)
				(justify left bottom)
				(hide yes)
			)
		)
		(property "Author" "Antmicro"
			(at 182.88 100.33 0)
			(effects
				(font
					(size 1.27 1.27)
					(thickness 0.15)
				)
				(justify left bottom)
				(hide yes)
			)
		)
		(property "Val" "0R"
			(at 203.835 71.12 0)
			(effects
				(font
					(size 1.27 1.27)
					(thickness 0.15)
				)
			)
		)
		(property "Tolerance" "~"
			(at 182.88 82.55 0)
			(effects
				(font
					(size 1.27 1.27)
				)
				(justify left bottom)
				(hide yes)
			)
		)
		(property "Current" "1A"
			(at 182.88 102.87 0)
			(effects
				(font
					(size 1.27 1.27)
					(thickness 0.15)
				)
				(justify left bottom)
				(hide yes)
			)
		)
		(pin "1"
		)
		(pin "2"
		)
		(instances
			(project "gmsl-deserializer"
				(path ""
					(reference "R5")
					(unit 1)
				)
			)
		)
	)
	(symbol
		(lib_id "antmicropower:GND")
		(at 303.53 186.69 0)
		(unit 1)
		(exclude_from_sim no)
		(in_bom yes)
		(on_board yes)
		(dnp no)
		(property "Reference" "#PWR0114"
			(at 312.42 189.23 0)
			(effects
				(font
					(size 1.27 1.27)
					(thickness 0.15)
				)
				(justify left bottom)
				(hide yes)
			)
		)
		(property "Value" "GND"
			(at 303.53 190.5 0)
			(effects
				(font
					(size 1.27 1.27)
					(thickness 0.15)
				)
			)
		)
		(property "Footprint" ""
			(at 312.42 194.31 0)
			(effects
				(font
					(size 1.27 1.27)
					(thickness 0.15)
				)
				(justify left bottom)
				(hide yes)
			)
		)
		(property "Datasheet" ""
			(at 312.42 199.39 0)
			(effects
				(font
					(size 1.27 1.27)
					(thickness 0.15)
				)
				(justify left bottom)
				(hide yes)
			)
		)
		(property "Description" ""
			(at 303.53 186.69 0)
			(effects
				(font
					(size 1.27 1.27)
				)
				(hide yes)
			)
		)
		(property "Author" "Antmicro"
			(at 312.42 194.31 0)
			(effects
				(font
					(size 1.27 1.27)
					(thickness 0.15)
				)
				(justify left bottom)
				(hide yes)
			)
		)
		(property "License" "Apache-2.0"
			(at 312.42 196.85 0)
			(effects
				(font
					(size 1.27 1.27)
					(thickness 0.15)
				)
				(justify left bottom)
				(hide yes)
			)
		)
		(pin "1"
		)
		(instances
			(project "gmsl-deserializer"
				(path ""
					(reference "#PWR0114")
					(unit 1)
				)
			)
		)
	)
	(symbol
		(lib_id "antmicroResistors0402:R_100R_0402")
		(at 298.45 162.56 0)
		(unit 1)
		(exclude_from_sim no)
		(in_bom yes)
		(on_board yes)
		(dnp no)
		(property "Reference" "R10"
			(at 298.45 161.29 0)
			(effects
				(font
					(size 1.27 1.27)
					(thickness 0.15)
				)
				(justify right)
			)
		)
		(property "Value" "R_100R_0402"
			(at 318.77 175.26 0)
			(effects
				(font
					(size 1.27 1.27)
					(thickness 0.15)
				)
				(justify left bottom)
				(hide yes)
			)
		)
		(property "Footprint" "antmicro-footprints:R_0402_1005Metric"
			(at 318.77 177.8 0)
			(effects
				(font
					(size 1.27 1.27)
					(thickness 0.15)
				)
				(justify left bottom)
				(hide yes)
			)
		)
		(property "Datasheet" "https://www.bourns.com/docs/product-datasheets/cr.pdf"
			(at 318.77 180.34 0)
			(effects
				(font
					(size 1.27 1.27)
					(thickness 0.15)
				)
				(justify left bottom)
				(hide yes)
			)
		)
		(property "Description" "SMD Chip Resistor, 100 ohm, ± 1%, 62.5 mW, 0402 [1005 Metric], Thick Film, General Purpose"
			(at 298.45 162.56 0)
			(effects
				(font
					(size 1.27 1.27)
				)
				(hide yes)
			)
		)
		(property "MPN" "CR0402-FX-1000GLF"
			(at 318.77 182.88 0)
			(effects
				(font
					(size 1.27 1.27)
					(thickness 0.15)
				)
				(justify left bottom)
				(hide yes)
			)
		)
		(property "Manufacturer" "Bourns"
			(at 318.77 185.42 0)
			(effects
				(font
					(size 1.27 1.27)
					(thickness 0.15)
				)
				(justify left bottom)
				(hide yes)
			)
		)
		(property "License" "Apache-2.0"
			(at 318.77 187.96 0)
			(effects
				(font
					(size 1.27 1.27)
					(thickness 0.15)
				)
				(justify left bottom)
				(hide yes)
			)
		)
		(property "Author" "Antmicro"
			(at 318.77 190.5 0)
			(effects
				(font
					(size 1.27 1.27)
					(thickness 0.15)
				)
				(justify left bottom)
				(hide yes)
			)
		)
		(property "Val" "100R"
			(at 306.07 161.29 0)
			(effects
				(font
					(size 1.27 1.27)
					(thickness 0.15)
				)
			)
		)
		(property "Tolerance" "1%"
			(at 318.77 172.72 0)
			(effects
				(font
					(size 1.27 1.27)
				)
				(justify left bottom)
				(hide yes)
			)
		)
		(pin "1"
		)
		(pin "2"
		)
		(instances
			(project "gmsl-deserializer"
				(path ""
					(reference "R10")
					(unit 1)
				)
			)
		)
	)
	(symbol
		(lib_id "antmicroCapacitors0603:C_10u_25V_0603")
		(at 34.29 76.2 90)
		(unit 1)
		(exclude_from_sim no)
		(in_bom yes)
		(on_board yes)
		(dnp no)
		(property "Reference" "C1"
			(at 36.83 72.3835 90)
			(effects
				(font
					(size 1.27 1.27)
					(thickness 0.15)
				)
				(justify right)
			)
		)
		(property "Value" "C_10u_25V_0603"
			(at 44.45 55.88 0)
			(effects
				(font
					(size 1.27 1.27)
					(thickness 0.15)
				)
				(justify left bottom)
				(hide yes)
			)
		)
		(property "Footprint" "antmicro-footprints:C_0603_1608Metric"
			(at 46.99 55.88 0)
			(effects
				(font
					(size 1.27 1.27)
					(thickness 0.15)
				)
				(justify left bottom)
				(hide yes)
			)
		)
		(property "Datasheet" "https://product.tdk.com/en/search/capacitor/ceramic/mlcc/info?part_no=C1608X5R1E106M080AC"
			(at 49.53 55.88 0)
			(effects
				(font
					(size 1.27 1.27)
					(thickness 0.15)
				)
				(justify left bottom)
				(hide yes)
			)
		)
		(property "Description" "SMD Multilayer Ceramic Capacitor, 10 µF, 25 V, 0603 [1608 Metric], ± 20%, X5R, C"
			(at 34.29 76.2 0)
			(effects
				(font
					(size 1.27 1.27)
				)
				(hide yes)
			)
		)
		(property "MPN" "C1608X5R1E106M080AC"
			(at 52.07 55.88 0)
			(effects
				(font
					(size 1.27 1.27)
					(thickness 0.15)
				)
				(justify left bottom)
				(hide yes)
			)
		)
		(property "Manufacturer" "TDK"
			(at 54.61 55.88 0)
			(effects
				(font
					(size 1.27 1.27)
					(thickness 0.15)
				)
				(justify left bottom)
				(hide yes)
			)
		)
		(property "License" "Apache-2.0"
			(at 57.15 55.88 0)
			(effects
				(font
					(size 1.27 1.27)
					(thickness 0.15)
				)
				(justify left bottom)
				(hide yes)
			)
		)
		(property "Author" "Antmicro"
			(at 59.69 55.88 0)
			(effects
				(font
					(size 1.27 1.27)
					(thickness 0.15)
				)
				(justify left bottom)
				(hide yes)
			)
		)
		(property "Val" "10u"
			(at 35.56 75.565 90)
			(effects
				(font
					(size 1.27 1.27)
					(thickness 0.15)
				)
				(justify right)
			)
		)
		(property "Voltage" "25V"
			(at 62.23 55.88 0)
			(effects
				(font
					(size 1.27 1.27)
				)
				(justify left bottom)
				(hide yes)
			)
		)
		(property "Dielectric" ""
			(at 64.77 55.88 0)
			(effects
				(font
					(size 1.27 1.27)
				)
				(justify left bottom)
				(hide yes)
			)
		)
		(pin "1"
		)
		(pin "2"
		)
		(instances
			(project "gmsl-deserializer"
				(path ""
					(reference "C1")
					(unit 1)
				)
			)
		)
	)
	(symbol
		(lib_id "antmicroCoaxialConnectorsRF:Conn_FAKRA_7-2287906-0")
		(at 153.67 233.68 0)
		(unit 1)
		(exclude_from_sim no)
		(in_bom yes)
		(on_board yes)
		(dnp no)
		(fields_autoplaced yes)
		(property "Reference" "J4"
			(at 162.56 232.7667 0)
			(effects
				(font
					(size 1.27 1.27)
					(thickness 0.15)
				)
				(justify left)
			)
		)
		(property "Value" "Conn_FAKRA_59S2AQ-40MT5-Z_1"
			(at 173.99 241.3 0)
			(effects
				(font
					(size 1.27 1.27)
					(thickness 0.15)
				)
				(justify left bottom)
				(hide yes)
			)
		)
		(property "Footprint" "antmicro-footprints:Conn_FAKRA_7-2287906-0"
			(at 173.99 243.84 0)
			(effects
				(font
					(size 1.27 1.27)
					(thickness 0.15)
				)
				(justify left bottom)
				(hide yes)
			)
		)
		(property "Datasheet" "https://www.te.com/en/product-7-2287906-0.html"
			(at 173.99 246.38 0)
			(effects
				(font
					(size 1.27 1.27)
					(thickness 0.15)
				)
				(justify left bottom)
				(hide yes)
			)
		)
		(property "Description" "FAKRA, 1 POS, ASSY EDGE MOUNT, 12OCLOCK"
			(at 153.67 233.68 0)
			(effects
				(font
					(size 1.27 1.27)
				)
				(hide yes)
			)
		)
		(property "MPN" "7-2287906-0"
			(at 162.56 235.3067 0)
			(effects
				(font
					(size 1.27 1.27)
					(thickness 0.15)
				)
				(justify left)
			)
		)
		(property "Manufacturer" "TE Connectivity"
			(at 173.99 251.46 0)
			(effects
				(font
					(size 1.27 1.27)
					(thickness 0.15)
				)
				(justify left bottom)
				(hide yes)
			)
		)
		(property "Author" "Antmicro"
			(at 173.99 254 0)
			(effects
				(font
					(size 1.27 1.27)
					(thickness 0.15)
				)
				(justify left bottom)
				(hide yes)
			)
		)
		(property "License" "Apache-2.0"
			(at 173.99 256.54 0)
			(effects
				(font
					(size 1.27 1.27)
					(thickness 0.15)
				)
				(justify left bottom)
				(hide yes)
			)
		)
		(pin "1"
		)
		(pin "2"
		)
		(pin "3"
		)
		(pin "4"
		)
		(pin "5"
		)
		(instances
			(project "gmsl-deserializer"
				(path ""
					(reference "J4")
					(unit 1)
				)
			)
		)
	)
	(symbol
		(lib_id "antmicropower:GND")
		(at 308.61 186.69 0)
		(unit 1)
		(exclude_from_sim no)
		(in_bom yes)
		(on_board yes)
		(dnp no)
		(property "Reference" "#PWR0116"
			(at 317.5 189.23 0)
			(effects
				(font
					(size 1.27 1.27)
					(thickness 0.15)
				)
				(justify left bottom)
				(hide yes)
			)
		)
		(property "Value" "GND"
			(at 308.61 190.5 0)
			(effects
				(font
					(size 1.27 1.27)
					(thickness 0.15)
				)
			)
		)
		(property "Footprint" ""
			(at 317.5 194.31 0)
			(effects
				(font
					(size 1.27 1.27)
					(thickness 0.15)
				)
				(justify left bottom)
				(hide yes)
			)
		)
		(property "Datasheet" ""
			(at 317.5 199.39 0)
			(effects
				(font
					(size 1.27 1.27)
					(thickness 0.15)
				)
				(justify left bottom)
				(hide yes)
			)
		)
		(property "Description" ""
			(at 308.61 186.69 0)
			(effects
				(font
					(size 1.27 1.27)
				)
				(hide yes)
			)
		)
		(property "Author" "Antmicro"
			(at 317.5 194.31 0)
			(effects
				(font
					(size 1.27 1.27)
					(thickness 0.15)
				)
				(justify left bottom)
				(hide yes)
			)
		)
		(property "License" "Apache-2.0"
			(at 317.5 196.85 0)
			(effects
				(font
					(size 1.27 1.27)
					(thickness 0.15)
				)
				(justify left bottom)
				(hide yes)
			)
		)
		(pin "1"
		)
		(instances
			(project "gmsl-deserializer"
				(path ""
					(reference "#PWR0116")
					(unit 1)
				)
			)
		)
	)
	(symbol
		(lib_id "antmicroTestPoints:TP_0.75mm_SMD")
		(at 317.5 200.66 90)
		(unit 1)
		(exclude_from_sim no)
		(in_bom yes)
		(on_board yes)
		(dnp no)
		(property "Reference" "TP7"
			(at 318.77 197.485 90)
			(effects
				(font
					(size 1.27 1.27)
					(thickness 0.15)
				)
				(justify right)
			)
		)
		(property "Value" "TP_0.75mm_SMD"
			(at 321.31 189.865 0)
			(effects
				(font
					(size 1.27 1.27)
					(thickness 0.15)
				)
				(justify left bottom)
				(hide yes)
			)
		)
		(property "Footprint" "antmicro-footprints:TP_SMD_0.75mm"
			(at 323.85 189.865 0)
			(effects
				(font
					(size 1.27 1.27)
					(thickness 0.15)
				)
				(justify left bottom)
				(hide yes)
			)
		)
		(property "Datasheet" ""
			(at 330.2 182.88 0)
			(effects
				(font
					(size 1.27 1.27)
					(thickness 0.15)
				)
				(justify left bottom)
				(hide yes)
			)
		)
		(property "Description" "SMT test point"
			(at 317.5 200.66 0)
			(effects
				(font
					(size 1.27 1.27)
				)
				(hide yes)
			)
		)
		(property "MPN" ""
			(at 328.93 189.865 0)
			(effects
				(font
					(size 1.27 1.27)
					(thickness 0.15)
				)
				(justify left bottom)
				(hide yes)
			)
		)
		(property "Manufacturer" ""
			(at 323.85 189.865 0)
			(effects
				(font
					(size 1.27 1.27)
					(thickness 0.15)
				)
				(justify left bottom)
				(hide yes)
			)
		)
		(property "Author" "Antmicro"
			(at 326.39 189.865 0)
			(effects
				(font
					(size 1.27 1.27)
					(thickness 0.15)
				)
				(justify left bottom)
				(hide yes)
			)
		)
		(property "License" "Apache-2.0"
			(at 328.93 189.865 0)
			(effects
				(font
					(size 1.27 1.27)
					(thickness 0.15)
				)
				(justify left bottom)
				(hide yes)
			)
		)
		(pin "1"
		)
		(instances
			(project "gmsl-deserializer"
				(path ""
					(reference "TP7")
					(unit 1)
				)
			)
		)
	)
	(symbol
		(lib_id "antmicroResistors0402:R_10k_0402")
		(at 173.99 78.74 90)
		(unit 1)
		(exclude_from_sim no)
		(in_bom yes)
		(on_board yes)
		(dnp no)
		(fields_autoplaced yes)
		(property "Reference" "R4"
			(at 175.895 74.9299 90)
			(effects
				(font
					(size 1.27 1.27)
					(thickness 0.15)
				)
				(justify right)
			)
		)
		(property "Value" "R_10k_0402"
			(at 186.69 58.42 0)
			(effects
				(font
					(size 1.27 1.27)
					(thickness 0.15)
				)
				(justify left bottom)
				(hide yes)
			)
		)
		(property "Footprint" "antmicro-footprints:R_0402_1005Metric"
			(at 189.23 58.42 0)
			(effects
				(font
					(size 1.27 1.27)
					(thickness 0.15)
				)
				(justify left bottom)
				(hide yes)
			)
		)
		(property "Datasheet" "https://www.bourns.com/docs/product-datasheets/cr.pdf"
			(at 191.77 58.42 0)
			(effects
				(font
					(size 1.27 1.27)
					(thickness 0.15)
				)
				(justify left bottom)
				(hide yes)
			)
		)
		(property "Description" "SMD Chip Resistor, 10 kohm, ± 1%, 62.5 mW, 0402 [1005 Metric], Thick Film, General Purpose"
			(at 173.99 78.74 0)
			(effects
				(font
					(size 1.27 1.27)
				)
				(hide yes)
			)
		)
		(property "MPN" "CR0402-FX-1002GLF"
			(at 194.31 58.42 0)
			(effects
				(font
					(size 1.27 1.27)
					(thickness 0.15)
				)
				(justify left bottom)
				(hide yes)
			)
		)
		(property "Manufacturer" "Bourns"
			(at 196.85 58.42 0)
			(effects
				(font
					(size 1.27 1.27)
					(thickness 0.15)
				)
				(justify left bottom)
				(hide yes)
			)
		)
		(property "License" "Apache-2.0"
			(at 199.39 58.42 0)
			(effects
				(font
					(size 1.27 1.27)
					(thickness 0.15)
				)
				(justify left bottom)
				(hide yes)
			)
		)
		(property "Author" "Antmicro"
			(at 201.93 58.42 0)
			(effects
				(font
					(size 1.27 1.27)
					(thickness 0.15)
				)
				(justify left bottom)
				(hide yes)
			)
		)
		(property "Val" "10k"
			(at 175.895 77.4699 90)
			(effects
				(font
					(size 1.27 1.27)
					(thickness 0.15)
				)
				(justify right)
			)
		)
		(property "Tolerance" "1%"
			(at 184.15 58.42 0)
			(effects
				(font
					(size 1.27 1.27)
				)
				(justify left bottom)
				(hide yes)
			)
		)
		(pin "1"
		)
		(pin "2"
		)
		(instances
			(project "gmsl-deserializer"
				(path ""
					(reference "R4")
					(unit 1)
				)
			)
		)
	)
	(symbol
		(lib_id "antmicroCapacitors0402:C_100n_0402")
		(at 200.66 62.23 90)
		(unit 1)
		(exclude_from_sim no)
		(in_bom yes)
		(on_board yes)
		(dnp no)
		(property "Reference" "C4"
			(at 202.565 58.42 90)
			(effects
				(font
					(size 1.27 1.27)
					(thickness 0.15)
				)
				(justify right)
			)
		)
		(property "Value" "C_100n_0402"
			(at 210.82 41.91 0)
			(effects
				(font
					(size 1.27 1.27)
					(thickness 0.15)
				)
				(justify left bottom)
				(hide yes)
			)
		)
		(property "Footprint" "antmicro-footprints:C_0402_1005Metric"
			(at 213.36 41.91 0)
			(effects
				(font
					(size 1.27 1.27)
					(thickness 0.15)
				)
				(justify left bottom)
				(hide yes)
			)
		)
		(property "Datasheet" "https://www.murata.com/products/productdetail?partno=GRM155R61H104KE14%23"
			(at 215.9 41.91 0)
			(effects
				(font
					(size 1.27 1.27)
					(thickness 0.15)
				)
				(justify left bottom)
				(hide yes)
			)
		)
		(property "Description" "SMD Multilayer Ceramic Capacitor, 0.1 µF, 50 V, 0402 [1005 Metric], ± 10%, X5R, GRM Series"
			(at 200.66 62.23 0)
			(effects
				(font
					(size 1.27 1.27)
				)
				(hide yes)
			)
		)
		(property "MPN" "GRM155R61H104KE14D"
			(at 218.44 41.91 0)
			(effects
				(font
					(size 1.27 1.27)
					(thickness 0.15)
				)
				(justify left bottom)
				(hide yes)
			)
		)
		(property "Manufacturer" "Murata"
			(at 220.98 41.91 0)
			(effects
				(font
					(size 1.27 1.27)
					(thickness 0.15)
				)
				(justify left bottom)
				(hide yes)
			)
		)
		(property "License" "Apache-2.0"
			(at 223.52 41.91 0)
			(effects
				(font
					(size 1.27 1.27)
					(thickness 0.15)
				)
				(justify left bottom)
				(hide yes)
			)
		)
		(property "Author" "Antmicro"
			(at 226.06 41.91 0)
			(effects
				(font
					(size 1.27 1.27)
					(thickness 0.15)
				)
				(justify left bottom)
				(hide yes)
			)
		)
		(property "Val" "100n"
			(at 202.565 60.96 90)
			(effects
				(font
					(size 1.27 1.27)
					(thickness 0.15)
				)
				(justify right)
			)
		)
		(property "Voltage" "50V"
			(at 228.6 41.91 0)
			(effects
				(font
					(size 1.27 1.27)
				)
				(justify left bottom)
				(hide yes)
			)
		)
		(property "Dielectric" "X5R"
			(at 231.14 41.91 0)
			(effects
				(font
					(size 1.27 1.27)
				)
				(justify left bottom)
				(hide yes)
			)
		)
		(pin "1"
		)
		(pin "2"
		)
		(instances
			(project "gmsl-deserializer"
				(path ""
					(reference "C4")
					(unit 1)
				)
			)
		)
	)
	(symbol
		(lib_id "antmicropower:GND")
		(at 349.25 209.55 0)
		(unit 1)
		(exclude_from_sim no)
		(in_bom yes)
		(on_board yes)
		(dnp no)
		(property "Reference" "#PWR019"
			(at 358.14 212.09 0)
			(effects
				(font
					(size 1.27 1.27)
					(thickness 0.15)
				)
				(justify left bottom)
				(hide yes)
			)
		)
		(property "Value" "GND"
			(at 349.25 213.36 0)
			(effects
				(font
					(size 1.27 1.27)
					(thickness 0.15)
				)
			)
		)
		(property "Footprint" ""
			(at 358.14 217.17 0)
			(effects
				(font
					(size 1.27 1.27)
					(thickness 0.15)
				)
				(justify left bottom)
				(hide yes)
			)
		)
		(property "Datasheet" ""
			(at 358.14 222.25 0)
			(effects
				(font
					(size 1.27 1.27)
					(thickness 0.15)
				)
				(justify left bottom)
				(hide yes)
			)
		)
		(property "Description" ""
			(at 349.25 209.55 0)
			(effects
				(font
					(size 1.27 1.27)
				)
				(hide yes)
			)
		)
		(property "Author" "Antmicro"
			(at 358.14 217.17 0)
			(effects
				(font
					(size 1.27 1.27)
					(thickness 0.15)
				)
				(justify left bottom)
				(hide yes)
			)
		)
		(property "License" "Apache-2.0"
			(at 358.14 219.71 0)
			(effects
				(font
					(size 1.27 1.27)
					(thickness 0.15)
				)
				(justify left bottom)
				(hide yes)
			)
		)
		(pin "1"
		)
		(instances
			(project "gmsl-deserializer"
				(path ""
					(reference "#PWR019")
					(unit 1)
				)
			)
		)
	)
	(symbol
		(lib_id "antmicroCapacitors0402:C_1u_0402")
		(at 330.2 207.01 90)
		(unit 1)
		(exclude_from_sim no)
		(in_bom yes)
		(on_board yes)
		(dnp no)
		(fields_autoplaced yes)
		(property "Reference" "C58"
			(at 332.74 203.1935 90)
			(effects
				(font
					(size 1.27 1.27)
					(thickness 0.15)
				)
				(justify right)
			)
		)
		(property "Value" "C_1u_0402"
			(at 340.36 186.69 0)
			(effects
				(font
					(size 1.27 1.27)
					(thickness 0.15)
				)
				(justify left bottom)
				(hide yes)
			)
		)
		(property "Footprint" "antmicro-footprints:C_0402_1005Metric"
			(at 342.9 186.69 0)
			(effects
				(font
					(size 1.27 1.27)
					(thickness 0.15)
				)
				(justify left bottom)
				(hide yes)
			)
		)
		(property "Datasheet" "https://product.tdk.com/en/search/capacitor/ceramic/mlcc/info?part_no=C1005X6S1A105K050BC"
			(at 345.44 186.69 0)
			(effects
				(font
					(size 1.27 1.27)
					(thickness 0.15)
				)
				(justify left bottom)
				(hide yes)
			)
		)
		(property "Description" "SMD Multilayer Ceramic Capacitor, 1 µF, 10 V, 0402 [1005 Metric], ± 10%, X6S, C"
			(at 330.2 207.01 0)
			(effects
				(font
					(size 1.27 1.27)
				)
				(hide yes)
			)
		)
		(property "MPN" "C1005X6S1A105K050BC"
			(at 347.98 186.69 0)
			(effects
				(font
					(size 1.27 1.27)
					(thickness 0.15)
				)
				(justify left bottom)
				(hide yes)
			)
		)
		(property "Manufacturer" "TDK"
			(at 350.52 186.69 0)
			(effects
				(font
					(size 1.27 1.27)
					(thickness 0.15)
				)
				(justify left bottom)
				(hide yes)
			)
		)
		(property "License" "Apache-2.0"
			(at 353.06 186.69 0)
			(effects
				(font
					(size 1.27 1.27)
					(thickness 0.15)
				)
				(justify left bottom)
				(hide yes)
			)
		)
		(property "Author" "Antmicro"
			(at 355.6 186.69 0)
			(effects
				(font
					(size 1.27 1.27)
					(thickness 0.15)
				)
				(justify left bottom)
				(hide yes)
			)
		)
		(property "Val" "1u"
			(at 332.74 205.7335 90)
			(effects
				(font
					(size 1.27 1.27)
					(thickness 0.15)
				)
				(justify right)
			)
		)
		(property "Voltage" ""
			(at 358.14 186.69 0)
			(effects
				(font
					(size 1.27 1.27)
				)
				(justify left bottom)
				(hide yes)
			)
		)
		(property "Dielectric" ""
			(at 360.68 186.69 0)
			(effects
				(font
					(size 1.27 1.27)
				)
				(justify left bottom)
				(hide yes)
			)
		)
		(pin "1"
		)
		(pin "2"
		)
		(instances
			(project "gmsl-deserializer"
				(path ""
					(reference "C58")
					(unit 1)
				)
			)
		)
	)
	(symbol
		(lib_id "antmicroTestPoints:TP_0.75mm_SMD")
		(at 102.87 130.81 90)
		(unit 1)
		(exclude_from_sim no)
		(in_bom yes)
		(on_board yes)
		(dnp no)
		(property "Reference" "TP25"
			(at 101.6 125.73 90)
			(effects
				(font
					(size 1.27 1.27)
					(thickness 0.15)
				)
				(justify right)
			)
		)
		(property "Value" "TP_0.75mm_SMD"
			(at 106.68 120.015 0)
			(effects
				(font
					(size 1.27 1.27)
					(thickness 0.15)
				)
				(justify left bottom)
				(hide yes)
			)
		)
		(property "Footprint" "antmicro-footprints:TP_SMD_0.75mm"
			(at 109.22 120.015 0)
			(effects
				(font
					(size 1.27 1.27)
					(thickness 0.15)
				)
				(justify left bottom)
				(hide yes)
			)
		)
		(property "Datasheet" ""
			(at 115.57 113.03 0)
			(effects
				(font
					(size 1.27 1.27)
					(thickness 0.15)
				)
				(justify left bottom)
				(hide yes)
			)
		)
		(property "Description" "SMT test point"
			(at 102.87 130.81 0)
			(effects
				(font
					(size 1.27 1.27)
				)
				(hide yes)
			)
		)
		(property "MPN" ""
			(at 114.3 120.015 0)
			(effects
				(font
					(size 1.27 1.27)
					(thickness 0.15)
				)
				(justify left bottom)
				(hide yes)
			)
		)
		(property "Manufacturer" ""
			(at 109.22 120.015 0)
			(effects
				(font
					(size 1.27 1.27)
					(thickness 0.15)
				)
				(justify left bottom)
				(hide yes)
			)
		)
		(property "Author" "Antmicro"
			(at 111.76 120.015 0)
			(effects
				(font
					(size 1.27 1.27)
					(thickness 0.15)
				)
				(justify left bottom)
				(hide yes)
			)
		)
		(property "License" "Apache-2.0"
			(at 114.3 120.015 0)
			(effects
				(font
					(size 1.27 1.27)
					(thickness 0.15)
				)
				(justify left bottom)
				(hide yes)
			)
		)
		(pin "1"
		)
		(instances
			(project "gmsl-deserializer"
				(path ""
					(reference "TP25")
					(unit 1)
				)
			)
		)
	)
	(symbol
		(lib_id "antmicroCoaxialConnectorsRF:Conn_FAKRA_7-2287906-0")
		(at 153.67 186.69 0)
		(unit 1)
		(exclude_from_sim no)
		(in_bom yes)
		(on_board yes)
		(dnp no)
		(fields_autoplaced yes)
		(property "Reference" "J2"
			(at 162.56 185.7767 0)
			(effects
				(font
					(size 1.27 1.27)
					(thickness 0.15)
				)
				(justify left)
			)
		)
		(property "Value" "Conn_FAKRA_59S2AQ-40MT5-Z_1"
			(at 173.99 194.31 0)
			(effects
				(font
					(size 1.27 1.27)
					(thickness 0.15)
				)
				(justify left bottom)
				(hide yes)
			)
		)
		(property "Footprint" "antmicro-footprints:Conn_FAKRA_7-2287906-0"
			(at 173.99 196.85 0)
			(effects
				(font
					(size 1.27 1.27)
					(thickness 0.15)
				)
				(justify left bottom)
				(hide yes)
			)
		)
		(property "Datasheet" "https://www.te.com/en/product-7-2287906-0.html"
			(at 173.99 199.39 0)
			(effects
				(font
					(size 1.27 1.27)
					(thickness 0.15)
				)
				(justify left bottom)
				(hide yes)
			)
		)
		(property "Description" "FAKRA, 1 POS, ASSY EDGE MOUNT, 12OCLOCK"
			(at 153.67 186.69 0)
			(effects
				(font
					(size 1.27 1.27)
				)
				(hide yes)
			)
		)
		(property "MPN" "7-2287906-0"
			(at 162.56 188.3167 0)
			(effects
				(font
					(size 1.27 1.27)
					(thickness 0.15)
				)
				(justify left)
			)
		)
		(property "Manufacturer" "TE Connectivity"
			(at 173.99 204.47 0)
			(effects
				(font
					(size 1.27 1.27)
					(thickness 0.15)
				)
				(justify left bottom)
				(hide yes)
			)
		)
		(property "Author" "Antmicro"
			(at 173.99 207.01 0)
			(effects
				(font
					(size 1.27 1.27)
					(thickness 0.15)
				)
				(justify left bottom)
				(hide yes)
			)
		)
		(property "License" "Apache-2.0"
			(at 173.99 209.55 0)
			(effects
				(font
					(size 1.27 1.27)
					(thickness 0.15)
				)
				(justify left bottom)
				(hide yes)
			)
		)
		(pin "1"
		)
		(pin "2"
		)
		(pin "3"
		)
		(pin "4"
		)
		(pin "5"
		)
		(instances
			(project "gmsl-deserializer"
				(path ""
					(reference "J2")
					(unit 1)
				)
			)
		)
	)
	(symbol
		(lib_id "antmicroResistors0402:R_40k2_0402")
		(at 27.94 242.57 90)
		(unit 1)
		(exclude_from_sim no)
		(in_bom yes)
		(on_board yes)
		(dnp no)
		(property "Reference" "R73"
			(at 30.48 238.76 90)
			(effects
				(font
					(size 1.27 1.27)
					(thickness 0.15)
				)
				(justify right)
			)
		)
		(property "Value" "R_40k2_0402"
			(at 40.64 222.25 0)
			(effects
				(font
					(size 1.27 1.27)
					(thickness 0.15)
				)
				(justify left bottom)
				(hide yes)
			)
		)
		(property "Footprint" "antmicro-footprints:R_0402_1005Metric"
			(at 43.18 222.25 0)
			(effects
				(font
					(size 1.27 1.27)
					(thickness 0.15)
				)
				(justify left bottom)
				(hide yes)
			)
		)
		(property "Datasheet" "https://www.bourns.com/docs/product-datasheets/cr.pdf"
			(at 45.72 222.25 0)
			(effects
				(font
					(size 1.27 1.27)
					(thickness 0.15)
				)
				(justify left bottom)
				(hide yes)
			)
		)
		(property "Description" "SMD Chip Resistor, 40.2 kohm, ± 1%, 63 mW, 0402 [1005 Metric], Thick Film, General Purpose"
			(at 27.94 242.57 0)
			(effects
				(font
					(size 1.27 1.27)
				)
				(hide yes)
			)
		)
		(property "MPN" "CR0402-FX-4022GLF"
			(at 48.26 222.25 0)
			(effects
				(font
					(size 1.27 1.27)
					(thickness 0.15)
				)
				(justify left bottom)
				(hide yes)
			)
		)
		(property "Manufacturer" "Bourns"
			(at 50.8 222.25 0)
			(effects
				(font
					(size 1.27 1.27)
					(thickness 0.15)
				)
				(justify left bottom)
				(hide yes)
			)
		)
		(property "License" "Apache-2.0"
			(at 53.34 222.25 0)
			(effects
				(font
					(size 1.27 1.27)
					(thickness 0.15)
				)
				(justify left bottom)
				(hide yes)
			)
		)
		(property "Author" "Antmicro"
			(at 55.88 222.25 0)
			(effects
				(font
					(size 1.27 1.27)
					(thickness 0.15)
				)
				(justify left bottom)
				(hide yes)
			)
		)
		(property "Val" "40k2"
			(at 30.48 241.3 90)
			(effects
				(font
					(size 1.27 1.27)
					(thickness 0.15)
				)
				(justify right)
			)
		)
		(property "Tolerance" "1%"
			(at 38.1 222.25 0)
			(effects
				(font
					(size 1.27 1.27)
				)
				(justify left bottom)
				(hide yes)
			)
		)
		(property "Public" ""
			(at 58.42 222.25 0)
			(effects
				(font
					(size 1.27 1.27)
				)
				(justify left bottom)
				(hide yes)
			)
		)
		(pin "1"
		)
		(pin "2"
		)
		(instances
			(project "gmsl-deserializer"
				(path ""
					(reference "R73")
					(unit 1)
				)
			)
		)
	)
	(symbol
		(lib_id "antmicropower:GND")
		(at 311.15 208.28 0)
		(unit 1)
		(exclude_from_sim no)
		(in_bom yes)
		(on_board yes)
		(dnp no)
		(property "Reference" "#PWR0117"
			(at 320.04 210.82 0)
			(effects
				(font
					(size 1.27 1.27)
					(thickness 0.15)
				)
				(justify left bottom)
				(hide yes)
			)
		)
		(property "Value" "GND"
			(at 311.15 212.09 0)
			(effects
				(font
					(size 1.27 1.27)
					(thickness 0.15)
				)
			)
		)
		(property "Footprint" ""
			(at 320.04 215.9 0)
			(effects
				(font
					(size 1.27 1.27)
					(thickness 0.15)
				)
				(justify left bottom)
				(hide yes)
			)
		)
		(property "Datasheet" ""
			(at 320.04 220.98 0)
			(effects
				(font
					(size 1.27 1.27)
					(thickness 0.15)
				)
				(justify left bottom)
				(hide yes)
			)
		)
		(property "Description" ""
			(at 311.15 208.28 0)
			(effects
				(font
					(size 1.27 1.27)
				)
				(hide yes)
			)
		)
		(property "Author" "Antmicro"
			(at 320.04 215.9 0)
			(effects
				(font
					(size 1.27 1.27)
					(thickness 0.15)
				)
				(justify left bottom)
				(hide yes)
			)
		)
		(property "License" "Apache-2.0"
			(at 320.04 218.44 0)
			(effects
				(font
					(size 1.27 1.27)
					(thickness 0.15)
				)
				(justify left bottom)
				(hide yes)
			)
		)
		(pin "1"
		)
		(instances
			(project "gmsl-deserializer"
				(path ""
					(reference "#PWR0117")
					(unit 1)
				)
			)
		)
	)
	(symbol
		(lib_id "antmicropower:GND")
		(at 71.12 228.6 0)
		(unit 1)
		(exclude_from_sim no)
		(in_bom yes)
		(on_board yes)
		(dnp no)
		(property "Reference" "#PWR0109"
			(at 80.01 231.14 0)
			(effects
				(font
					(size 1.27 1.27)
					(thickness 0.15)
				)
				(justify left bottom)
				(hide yes)
			)
		)
		(property "Value" "GND"
			(at 71.12 232.41 0)
			(effects
				(font
					(size 1.27 1.27)
					(thickness 0.15)
				)
			)
		)
		(property "Footprint" ""
			(at 80.01 236.22 0)
			(effects
				(font
					(size 1.27 1.27)
					(thickness 0.15)
				)
				(justify left bottom)
				(hide yes)
			)
		)
		(property "Datasheet" ""
			(at 80.01 241.3 0)
			(effects
				(font
					(size 1.27 1.27)
					(thickness 0.15)
				)
				(justify left bottom)
				(hide yes)
			)
		)
		(property "Description" ""
			(at 71.12 228.6 0)
			(effects
				(font
					(size 1.27 1.27)
				)
				(hide yes)
			)
		)
		(property "Author" "Antmicro"
			(at 80.01 236.22 0)
			(effects
				(font
					(size 1.27 1.27)
					(thickness 0.15)
				)
				(justify left bottom)
				(hide yes)
			)
		)
		(property "License" "Apache-2.0"
			(at 80.01 238.76 0)
			(effects
				(font
					(size 1.27 1.27)
					(thickness 0.15)
				)
				(justify left bottom)
				(hide yes)
			)
		)
		(pin "1"
		)
		(instances
			(project "gmsl-deserializer"
				(path ""
					(reference "#PWR0109")
					(unit 1)
				)
			)
		)
	)
	(symbol
		(lib_id "antmicroCapacitors0402:C_1u_0402")
		(at 337.82 207.01 90)
		(unit 1)
		(exclude_from_sim no)
		(in_bom yes)
		(on_board yes)
		(dnp no)
		(fields_autoplaced yes)
		(property "Reference" "C5"
			(at 340.36 203.1935 90)
			(effects
				(font
					(size 1.27 1.27)
					(thickness 0.15)
				)
				(justify right)
			)
		)
		(property "Value" "C_1u_0402"
			(at 347.98 186.69 0)
			(effects
				(font
					(size 1.27 1.27)
					(thickness 0.15)
				)
				(justify left bottom)
				(hide yes)
			)
		)
		(property "Footprint" "antmicro-footprints:C_0402_1005Metric"
			(at 350.52 186.69 0)
			(effects
				(font
					(size 1.27 1.27)
					(thickness 0.15)
				)
				(justify left bottom)
				(hide yes)
			)
		)
		(property "Datasheet" "https://product.tdk.com/en/search/capacitor/ceramic/mlcc/info?part_no=C1005X6S1A105K050BC"
			(at 353.06 186.69 0)
			(effects
				(font
					(size 1.27 1.27)
					(thickness 0.15)
				)
				(justify left bottom)
				(hide yes)
			)
		)
		(property "Description" "SMD Multilayer Ceramic Capacitor, 1 µF, 10 V, 0402 [1005 Metric], ± 10%, X6S, C"
			(at 337.82 207.01 0)
			(effects
				(font
					(size 1.27 1.27)
				)
				(hide yes)
			)
		)
		(property "MPN" "C1005X6S1A105K050BC"
			(at 355.6 186.69 0)
			(effects
				(font
					(size 1.27 1.27)
					(thickness 0.15)
				)
				(justify left bottom)
				(hide yes)
			)
		)
		(property "Manufacturer" "TDK"
			(at 358.14 186.69 0)
			(effects
				(font
					(size 1.27 1.27)
					(thickness 0.15)
				)
				(justify left bottom)
				(hide yes)
			)
		)
		(property "License" "Apache-2.0"
			(at 360.68 186.69 0)
			(effects
				(font
					(size 1.27 1.27)
					(thickness 0.15)
				)
				(justify left bottom)
				(hide yes)
			)
		)
		(property "Author" "Antmicro"
			(at 363.22 186.69 0)
			(effects
				(font
					(size 1.27 1.27)
					(thickness 0.15)
				)
				(justify left bottom)
				(hide yes)
			)
		)
		(property "Val" "1u"
			(at 340.36 205.7335 90)
			(effects
				(font
					(size 1.27 1.27)
					(thickness 0.15)
				)
				(justify right)
			)
		)
		(property "Voltage" ""
			(at 365.76 186.69 0)
			(effects
				(font
					(size 1.27 1.27)
				)
				(justify left bottom)
				(hide yes)
			)
		)
		(property "Dielectric" ""
			(at 368.3 186.69 0)
			(effects
				(font
					(size 1.27 1.27)
				)
				(justify left bottom)
				(hide yes)
			)
		)
		(pin "1"
		)
		(pin "2"
		)
		(instances
			(project "gmsl-deserializer"
				(path ""
					(reference "C5")
					(unit 1)
				)
			)
		)
	)
	(symbol
		(lib_id "antmicroTestPoints:TP_0.75mm_SMD")
		(at 53.34 205.74 0)
		(unit 1)
		(exclude_from_sim no)
		(in_bom yes)
		(on_board yes)
		(dnp no)
		(fields_autoplaced yes)
		(property "Reference" "TP4"
			(at 58.42 205.7399 0)
			(effects
				(font
					(size 1.27 1.27)
					(thickness 0.15)
				)
				(justify left)
			)
		)
		(property "Value" "TP_0.75mm_SMD"
			(at 64.135 209.55 0)
			(effects
				(font
					(size 1.27 1.27)
					(thickness 0.15)
				)
				(justify left bottom)
				(hide yes)
			)
		)
		(property "Footprint" "antmicro-footprints:TP_SMD_0.75mm"
			(at 64.135 212.09 0)
			(effects
				(font
					(size 1.27 1.27)
					(thickness 0.15)
				)
				(justify left bottom)
				(hide yes)
			)
		)
		(property "Datasheet" ""
			(at 71.12 218.44 0)
			(effects
				(font
					(size 1.27 1.27)
					(thickness 0.15)
				)
				(justify left bottom)
				(hide yes)
			)
		)
		(property "Description" "SMT test point"
			(at 53.34 205.74 0)
			(effects
				(font
					(size 1.27 1.27)
				)
				(hide yes)
			)
		)
		(property "MPN" ""
			(at 64.135 217.17 0)
			(effects
				(font
					(size 1.27 1.27)
					(thickness 0.15)
				)
				(justify left bottom)
				(hide yes)
			)
		)
		(property "Manufacturer" ""
			(at 64.135 212.09 0)
			(effects
				(font
					(size 1.27 1.27)
					(thickness 0.15)
				)
				(justify left bottom)
				(hide yes)
			)
		)
		(property "Author" "Antmicro"
			(at 64.135 214.63 0)
			(effects
				(font
					(size 1.27 1.27)
					(thickness 0.15)
				)
				(justify left bottom)
				(hide yes)
			)
		)
		(property "License" "Apache-2.0"
			(at 64.135 217.17 0)
			(effects
				(font
					(size 1.27 1.27)
					(thickness 0.15)
				)
				(justify left bottom)
				(hide yes)
			)
		)
		(pin "1"
		)
		(instances
			(project "gmsl-deserializer"
				(path ""
					(reference "TP4")
					(unit 1)
				)
			)
		)
	)
	(symbol
		(lib_id "antmicroFuses:F_4A_1206")
		(at 62.23 69.85 0)
		(unit 1)
		(exclude_from_sim no)
		(in_bom yes)
		(on_board yes)
		(dnp no)
		(fields_autoplaced yes)
		(property "Reference" "F1"
			(at 64.77 64.77 0)
			(effects
				(font
					(size 1.27 1.27)
					(thickness 0.15)
				)
			)
		)
		(property "Value" "F_4A_1206"
			(at 82.55 77.47 0)
			(effects
				(font
					(size 1.27 1.27)
					(thickness 0.15)
				)
				(justify left bottom)
				(hide yes)
			)
		)
		(property "Footprint" "antmicro-footprints:F_1206_3216Metric"
			(at 82.55 80.01 0)
			(effects
				(font
					(size 1.27 1.27)
					(thickness 0.15)
				)
				(justify left bottom)
				(hide yes)
			)
		)
		(property "Datasheet" "https://www.littelfuse.com/media?resourcetype=datasheets&itemid=dbe9bcd7-6072-4adf-bf5b-d33e52a6b90f&filename=littelfuse-fuse-466-datasheet"
			(at 82.55 82.55 0)
			(effects
				(font
					(size 1.27 1.27)
					(thickness 0.15)
				)
				(justify left bottom)
				(hide yes)
			)
		)
		(property "Description" "Fuse, Surface Mount, 4 A, Very Fast Acting, 32 V, 32 V, 1206 (3216 Metric), 466"
			(at 62.23 69.85 0)
			(effects
				(font
					(size 1.27 1.27)
				)
				(hide yes)
			)
		)
		(property "Manufacturer" "Littelfuse"
			(at 82.55 85.09 0)
			(effects
				(font
					(size 1.27 1.27)
					(thickness 0.15)
				)
				(justify left bottom)
				(hide yes)
			)
		)
		(property "MPN" "0466004.NR "
			(at 64.77 67.31 0)
			(effects
				(font
					(size 1.27 1.27)
					(thickness 0.15)
				)
			)
		)
		(property "Author" "Antmicro"
			(at 82.55 90.17 0)
			(effects
				(font
					(size 1.27 1.27)
					(thickness 0.15)
				)
				(justify left bottom)
				(hide yes)
			)
		)
		(property "License" "Apache-2.0"
			(at 82.55 92.71 0)
			(effects
				(font
					(size 1.27 1.27)
					(thickness 0.15)
				)
				(justify left bottom)
				(hide yes)
			)
		)
		(pin "1"
		)
		(pin "2"
		)
		(instances
			(project "gmsl-deserializer"
				(path ""
					(reference "F1")
					(unit 1)
				)
			)
		)
	)
	(symbol
		(lib_id "antmicropower:GND")
		(at 132.08 120.65 0)
		(mirror y)
		(unit 1)
		(exclude_from_sim no)
		(in_bom yes)
		(on_board yes)
		(dnp no)
		(property "Reference" "#PWR03"
			(at 123.19 123.19 0)
			(effects
				(font
					(size 1.27 1.27)
					(thickness 0.15)
				)
				(justify left bottom)
				(hide yes)
			)
		)
		(property "Value" "GND"
			(at 132.08 124.46 0)
			(effects
				(font
					(size 1.27 1.27)
					(thickness 0.15)
				)
			)
		)
		(property "Footprint" ""
			(at 123.19 128.27 0)
			(effects
				(font
					(size 1.27 1.27)
					(thickness 0.15)
				)
				(justify left bottom)
				(hide yes)
			)
		)
		(property "Datasheet" ""
			(at 123.19 133.35 0)
			(effects
				(font
					(size 1.27 1.27)
					(thickness 0.15)
				)
				(justify left bottom)
				(hide yes)
			)
		)
		(property "Description" ""
			(at 132.08 120.65 0)
			(effects
				(font
					(size 1.27 1.27)
				)
				(hide yes)
			)
		)
		(property "Author" "Antmicro"
			(at 123.19 128.27 0)
			(effects
				(font
					(size 1.27 1.27)
					(thickness 0.15)
				)
				(justify left bottom)
				(hide yes)
			)
		)
		(property "License" "Apache-2.0"
			(at 123.19 130.81 0)
			(effects
				(font
					(size 1.27 1.27)
					(thickness 0.15)
				)
				(justify left bottom)
				(hide yes)
			)
		)
		(pin "1"
		)
		(instances
			(project "gmsl-deserializer"
				(path ""
					(reference "#PWR03")
					(unit 1)
				)
			)
		)
	)
	(symbol
		(lib_id "antmicropower:GND")
		(at 27.94 77.47 0)
		(unit 1)
		(exclude_from_sim no)
		(in_bom yes)
		(on_board yes)
		(dnp no)
		(property "Reference" "#PWR0101"
			(at 36.83 80.01 0)
			(effects
				(font
					(size 1.27 1.27)
					(thickness 0.15)
				)
				(justify left bottom)
				(hide yes)
			)
		)
		(property "Value" "GND"
			(at 27.94 81.28 0)
			(effects
				(font
					(size 1.27 1.27)
					(thickness 0.15)
				)
			)
		)
		(property "Footprint" ""
			(at 36.83 85.09 0)
			(effects
				(font
					(size 1.27 1.27)
					(thickness 0.15)
				)
				(justify left bottom)
				(hide yes)
			)
		)
		(property "Datasheet" ""
			(at 36.83 90.17 0)
			(effects
				(font
					(size 1.27 1.27)
					(thickness 0.15)
				)
				(justify left bottom)
				(hide yes)
			)
		)
		(property "Description" ""
			(at 27.94 77.47 0)
			(effects
				(font
					(size 1.27 1.27)
				)
				(hide yes)
			)
		)
		(property "Author" "Antmicro"
			(at 36.83 85.09 0)
			(effects
				(font
					(size 1.27 1.27)
					(thickness 0.15)
				)
				(justify left bottom)
				(hide yes)
			)
		)
		(property "License" "Apache-2.0"
			(at 36.83 87.63 0)
			(effects
				(font
					(size 1.27 1.27)
					(thickness 0.15)
				)
				(justify left bottom)
				(hide yes)
			)
		)
		(pin "1"
		)
		(instances
			(project "gmsl-deserializer"
				(path ""
					(reference "#PWR0101")
					(unit 1)
				)
			)
		)
	)
	(symbol
		(lib_id "antmicroResistors0402:R_470R_0402")
		(at 266.7 223.52 90)
		(unit 1)
		(exclude_from_sim no)
		(in_bom yes)
		(on_board yes)
		(dnp no)
		(fields_autoplaced yes)
		(property "Reference" "R71"
			(at 269.24 219.7099 90)
			(effects
				(font
					(size 1.27 1.27)
					(thickness 0.15)
				)
				(justify right)
			)
		)
		(property "Value" "R_470R_0402"
			(at 279.4 203.2 0)
			(effects
				(font
					(size 1.27 1.27)
					(thickness 0.15)
				)
				(justify left bottom)
				(hide yes)
			)
		)
		(property "Footprint" "antmicro-footprints:R_0402_1005Metric"
			(at 281.94 203.2 0)
			(effects
				(font
					(size 1.27 1.27)
					(thickness 0.15)
				)
				(justify left bottom)
				(hide yes)
			)
		)
		(property "Datasheet" "https://www.bourns.com/docs/product-datasheets/cr.pdf"
			(at 284.48 203.2 0)
			(effects
				(font
					(size 1.27 1.27)
					(thickness 0.15)
				)
				(justify left bottom)
				(hide yes)
			)
		)
		(property "Description" "SMD Chip Resistor, 470 ohm, ± 1%, 62.5 mW, 0402 [1005 Metric], Thick Film, General Purpose"
			(at 266.7 223.52 0)
			(effects
				(font
					(size 1.27 1.27)
				)
				(hide yes)
			)
		)
		(property "MPN" "CR0402-FX-4700GLF"
			(at 287.02 203.2 0)
			(effects
				(font
					(size 1.27 1.27)
					(thickness 0.15)
				)
				(justify left bottom)
				(hide yes)
			)
		)
		(property "Manufacturer" "Bourns"
			(at 289.56 203.2 0)
			(effects
				(font
					(size 1.27 1.27)
					(thickness 0.15)
				)
				(justify left bottom)
				(hide yes)
			)
		)
		(property "License" "Apache-2.0"
			(at 292.1 203.2 0)
			(effects
				(font
					(size 1.27 1.27)
					(thickness 0.15)
				)
				(justify left bottom)
				(hide yes)
			)
		)
		(property "Author" "Antmicro"
			(at 294.64 203.2 0)
			(effects
				(font
					(size 1.27 1.27)
					(thickness 0.15)
				)
				(justify left bottom)
				(hide yes)
			)
		)
		(property "Val" "470R"
			(at 269.24 222.2499 90)
			(effects
				(font
					(size 1.27 1.27)
					(thickness 0.15)
				)
				(justify right)
			)
		)
		(property "Tolerance" "1%"
			(at 276.86 203.2 0)
			(effects
				(font
					(size 1.27 1.27)
				)
				(justify left bottom)
				(hide yes)
			)
		)
		(pin "1"
		)
		(pin "2"
		)
		(instances
			(project "gmsl-deserializer"
				(path ""
					(reference "R71")
					(unit 1)
				)
			)
		)
	)
	(symbol
		(lib_id "antmicroResistors0402:R_100R_0402")
		(at 114.3 143.51 0)
		(unit 1)
		(exclude_from_sim no)
		(in_bom no)
		(on_board yes)
		(dnp yes)
		(property "Reference" "R69"
			(at 114.3 142.24 0)
			(effects
				(font
					(size 1.27 1.27)
					(thickness 0.15)
				)
				(justify right)
			)
		)
		(property "Value" "R_100R_0402"
			(at 134.62 156.21 0)
			(effects
				(font
					(size 1.27 1.27)
					(thickness 0.15)
				)
				(justify left bottom)
				(hide yes)
			)
		)
		(property "Footprint" "antmicro-footprints:R_0402_1005Metric"
			(at 134.62 158.75 0)
			(effects
				(font
					(size 1.27 1.27)
					(thickness 0.15)
				)
				(justify left bottom)
				(hide yes)
			)
		)
		(property "Datasheet" "https://www.bourns.com/docs/product-datasheets/cr.pdf"
			(at 134.62 161.29 0)
			(effects
				(font
					(size 1.27 1.27)
					(thickness 0.15)
				)
				(justify left bottom)
				(hide yes)
			)
		)
		(property "Description" "SMD Chip Resistor, 100 ohm, ± 1%, 62.5 mW, 0402 [1005 Metric], Thick Film, General Purpose"
			(at 114.3 143.51 0)
			(effects
				(font
					(size 1.27 1.27)
				)
				(hide yes)
			)
		)
		(property "MPN" "CR0402-FX-1000GLF"
			(at 134.62 163.83 0)
			(effects
				(font
					(size 1.27 1.27)
					(thickness 0.15)
				)
				(justify left bottom)
				(hide yes)
			)
		)
		(property "Manufacturer" "Bourns"
			(at 134.62 166.37 0)
			(effects
				(font
					(size 1.27 1.27)
					(thickness 0.15)
				)
				(justify left bottom)
				(hide yes)
			)
		)
		(property "License" "Apache-2.0"
			(at 134.62 168.91 0)
			(effects
				(font
					(size 1.27 1.27)
					(thickness 0.15)
				)
				(justify left bottom)
				(hide yes)
			)
		)
		(property "Author" "Antmicro"
			(at 134.62 171.45 0)
			(effects
				(font
					(size 1.27 1.27)
					(thickness 0.15)
				)
				(justify left bottom)
				(hide yes)
			)
		)
		(property "Val" "100R"
			(at 121.92 142.24 0)
			(effects
				(font
					(size 1.27 1.27)
					(thickness 0.15)
				)
			)
		)
		(property "Tolerance" "1%"
			(at 134.62 153.67 0)
			(effects
				(font
					(size 1.27 1.27)
				)
				(justify left bottom)
				(hide yes)
			)
		)
		(pin "1"
		)
		(pin "2"
		)
		(instances
			(project "gmsl-deserializer"
				(path ""
					(reference "R69")
					(unit 1)
				)
			)
		)
	)
	(symbol
		(lib_id "antmicropower:GND")
		(at 146.05 63.5 0)
		(unit 1)
		(exclude_from_sim no)
		(in_bom yes)
		(on_board yes)
		(dnp no)
		(property "Reference" "#PWR012"
			(at 154.94 66.04 0)
			(effects
				(font
					(size 1.27 1.27)
					(thickness 0.15)
				)
				(justify left bottom)
				(hide yes)
			)
		)
		(property "Value" "GND"
			(at 146.05 67.31 0)
			(effects
				(font
					(size 1.27 1.27)
					(thickness 0.15)
				)
			)
		)
		(property "Footprint" ""
			(at 154.94 71.12 0)
			(effects
				(font
					(size 1.27 1.27)
					(thickness 0.15)
				)
				(justify left bottom)
				(hide yes)
			)
		)
		(property "Datasheet" ""
			(at 154.94 76.2 0)
			(effects
				(font
					(size 1.27 1.27)
					(thickness 0.15)
				)
				(justify left bottom)
				(hide yes)
			)
		)
		(property "Description" ""
			(at 146.05 63.5 0)
			(effects
				(font
					(size 1.27 1.27)
				)
				(hide yes)
			)
		)
		(property "Author" "Antmicro"
			(at 154.94 71.12 0)
			(effects
				(font
					(size 1.27 1.27)
					(thickness 0.15)
				)
				(justify left bottom)
				(hide yes)
			)
		)
		(property "License" "Apache-2.0"
			(at 154.94 73.66 0)
			(effects
				(font
					(size 1.27 1.27)
					(thickness 0.15)
				)
				(justify left bottom)
				(hide yes)
			)
		)
		(pin "1"
		)
		(instances
			(project "gmsl-deserializer"
				(path ""
					(reference "#PWR012")
					(unit 1)
				)
			)
		)
	)
	(symbol
		(lib_id "antmicroResistors0402:R_2k2_0402")
		(at 127 130.81 90)
		(unit 1)
		(exclude_from_sim no)
		(in_bom yes)
		(on_board yes)
		(dnp no)
		(property "Reference" "R59"
			(at 128.27 127 90)
			(effects
				(font
					(size 1.27 1.27)
					(thickness 0.15)
				)
				(justify right)
			)
		)
		(property "Value" "R_2k2_0402"
			(at 139.7 110.49 0)
			(effects
				(font
					(size 1.27 1.27)
					(thickness 0.15)
				)
				(justify left bottom)
				(hide yes)
			)
		)
		(property "Footprint" "antmicro-footprints:R_0402_1005Metric"
			(at 142.24 110.49 0)
			(effects
				(font
					(size 1.27 1.27)
					(thickness 0.15)
				)
				(justify left bottom)
				(hide yes)
			)
		)
		(property "Datasheet" "https://www.bourns.com/docs/product-datasheets/cr.pdf"
			(at 144.78 110.49 0)
			(effects
				(font
					(size 1.27 1.27)
					(thickness 0.15)
				)
				(justify left bottom)
				(hide yes)
			)
		)
		(property "Description" "SMD Chip Resistor, 2.2 kohm, ± 1%, 62.5 mW, 0402 [1005 Metric], Thick Film, General Purpose"
			(at 127 130.81 0)
			(effects
				(font
					(size 1.27 1.27)
				)
				(hide yes)
			)
		)
		(property "MPN" "CR0402-FX-2201GLF"
			(at 147.32 110.49 0)
			(effects
				(font
					(size 1.27 1.27)
					(thickness 0.15)
				)
				(justify left bottom)
				(hide yes)
			)
		)
		(property "Manufacturer" "Bourns"
			(at 149.86 110.49 0)
			(effects
				(font
					(size 1.27 1.27)
					(thickness 0.15)
				)
				(justify left bottom)
				(hide yes)
			)
		)
		(property "License" "Apache-2.0"
			(at 152.4 110.49 0)
			(effects
				(font
					(size 1.27 1.27)
					(thickness 0.15)
				)
				(justify left bottom)
				(hide yes)
			)
		)
		(property "Author" "Antmicro"
			(at 154.94 110.49 0)
			(effects
				(font
					(size 1.27 1.27)
					(thickness 0.15)
				)
				(justify left bottom)
				(hide yes)
			)
		)
		(property "Val" "2k2"
			(at 128.27 129.54 90)
			(effects
				(font
					(size 1.27 1.27)
					(thickness 0.15)
				)
				(justify right)
			)
		)
		(property "Tolerance" "1%"
			(at 137.16 110.49 0)
			(effects
				(font
					(size 1.27 1.27)
				)
				(justify left bottom)
				(hide yes)
			)
		)
		(pin "1"
		)
		(pin "2"
		)
		(instances
			(project "gmsl-deserializer"
				(path ""
					(reference "R59")
					(unit 1)
				)
			)
		)
	)
	(symbol
		(lib_id "antmicroResistors0402:R_2k2_0402")
		(at 120.65 130.81 90)
		(unit 1)
		(exclude_from_sim no)
		(in_bom yes)
		(on_board yes)
		(dnp no)
		(property "Reference" "R58"
			(at 121.92 127 90)
			(effects
				(font
					(size 1.27 1.27)
					(thickness 0.15)
				)
				(justify right)
			)
		)
		(property "Value" "R_2k2_0402"
			(at 133.35 110.49 0)
			(effects
				(font
					(size 1.27 1.27)
					(thickness 0.15)
				)
				(justify left bottom)
				(hide yes)
			)
		)
		(property "Footprint" "antmicro-footprints:R_0402_1005Metric"
			(at 135.89 110.49 0)
			(effects
				(font
					(size 1.27 1.27)
					(thickness 0.15)
				)
				(justify left bottom)
				(hide yes)
			)
		)
		(property "Datasheet" "https://www.bourns.com/docs/product-datasheets/cr.pdf"
			(at 138.43 110.49 0)
			(effects
				(font
					(size 1.27 1.27)
					(thickness 0.15)
				)
				(justify left bottom)
				(hide yes)
			)
		)
		(property "Description" "SMD Chip Resistor, 2.2 kohm, ± 1%, 62.5 mW, 0402 [1005 Metric], Thick Film, General Purpose"
			(at 120.65 130.81 0)
			(effects
				(font
					(size 1.27 1.27)
				)
				(hide yes)
			)
		)
		(property "MPN" "CR0402-FX-2201GLF"
			(at 140.97 110.49 0)
			(effects
				(font
					(size 1.27 1.27)
					(thickness 0.15)
				)
				(justify left bottom)
				(hide yes)
			)
		)
		(property "Manufacturer" "Bourns"
			(at 143.51 110.49 0)
			(effects
				(font
					(size 1.27 1.27)
					(thickness 0.15)
				)
				(justify left bottom)
				(hide yes)
			)
		)
		(property "License" "Apache-2.0"
			(at 146.05 110.49 0)
			(effects
				(font
					(size 1.27 1.27)
					(thickness 0.15)
				)
				(justify left bottom)
				(hide yes)
			)
		)
		(property "Author" "Antmicro"
			(at 148.59 110.49 0)
			(effects
				(font
					(size 1.27 1.27)
					(thickness 0.15)
				)
				(justify left bottom)
				(hide yes)
			)
		)
		(property "Val" "2k2"
			(at 121.92 129.54 90)
			(effects
				(font
					(size 1.27 1.27)
					(thickness 0.15)
				)
				(justify right)
			)
		)
		(property "Tolerance" "1%"
			(at 130.81 110.49 0)
			(effects
				(font
					(size 1.27 1.27)
				)
				(justify left bottom)
				(hide yes)
			)
		)
		(pin "1"
		)
		(pin "2"
		)
		(instances
			(project "gmsl-deserializer"
				(path ""
					(reference "R58")
					(unit 1)
				)
			)
		)
	)
	(symbol
		(lib_id "antmicroResistors0402:R_0R_0402")
		(at 203.2 76.2 0)
		(mirror y)
		(unit 1)
		(exclude_from_sim no)
		(in_bom yes)
		(on_board yes)
		(dnp no)
		(property "Reference" "R6"
			(at 196.85 74.93 0)
			(effects
				(font
					(size 1.27 1.27)
					(thickness 0.15)
				)
			)
		)
		(property "Value" "R_0R_0402"
			(at 182.88 88.9 0)
			(effects
				(font
					(size 1.27 1.27)
					(thickness 0.15)
				)
				(justify left bottom)
				(hide yes)
			)
		)
		(property "Footprint" "antmicro-footprints:R_0402_1005Metric"
			(at 182.88 91.44 0)
			(effects
				(font
					(size 1.27 1.27)
					(thickness 0.15)
				)
				(justify left bottom)
				(hide yes)
			)
		)
		(property "Datasheet" "https://industrial.panasonic.com/cdbs/www-data/pdf/RDA0000/AOA0000C301.pdf"
			(at 182.88 93.98 0)
			(effects
				(font
					(size 1.27 1.27)
					(thickness 0.15)
				)
				(justify left bottom)
				(hide yes)
			)
		)
		(property "Description" "SMD Chip Resistor, Jumper, 0 ohm, 100 mW, 0402 [1005 Metric], Thick Film, General Purpose"
			(at 203.2 76.2 0)
			(effects
				(font
					(size 1.27 1.27)
				)
				(hide yes)
			)
		)
		(property "MPN" "ERJ2GE0R00X"
			(at 182.88 96.52 0)
			(effects
				(font
					(size 1.27 1.27)
					(thickness 0.15)
				)
				(justify left bottom)
				(hide yes)
			)
		)
		(property "Manufacturer" "Panasonic"
			(at 182.88 99.06 0)
			(effects
				(font
					(size 1.27 1.27)
					(thickness 0.15)
				)
				(justify left bottom)
				(hide yes)
			)
		)
		(property "License" "Apache-2.0"
			(at 182.88 101.6 0)
			(effects
				(font
					(size 1.27 1.27)
					(thickness 0.15)
				)
				(justify left bottom)
				(hide yes)
			)
		)
		(property "Author" "Antmicro"
			(at 182.88 104.14 0)
			(effects
				(font
					(size 1.27 1.27)
					(thickness 0.15)
				)
				(justify left bottom)
				(hide yes)
			)
		)
		(property "Val" "0R"
			(at 203.835 74.93 0)
			(effects
				(font
					(size 1.27 1.27)
					(thickness 0.15)
				)
			)
		)
		(property "Tolerance" "~"
			(at 182.88 86.36 0)
			(effects
				(font
					(size 1.27 1.27)
				)
				(justify left bottom)
				(hide yes)
			)
		)
		(property "Current" "1A"
			(at 182.88 106.68 0)
			(effects
				(font
					(size 1.27 1.27)
					(thickness 0.15)
				)
				(justify left bottom)
				(hide yes)
			)
		)
		(pin "1"
		)
		(pin "2"
		)
		(instances
			(project "gmsl-deserializer"
				(path ""
					(reference "R6")
					(unit 1)
				)
			)
		)
	)
	(symbol
		(lib_id "antmicropower:GND")
		(at 158.75 193.04 0)
		(unit 1)
		(exclude_from_sim no)
		(in_bom yes)
		(on_board yes)
		(dnp no)
		(property "Reference" "#PWR0108"
			(at 167.64 195.58 0)
			(effects
				(font
					(size 1.27 1.27)
					(thickness 0.15)
				)
				(justify left bottom)
				(hide yes)
			)
		)
		(property "Value" "GND"
			(at 158.75 196.85 0)
			(effects
				(font
					(size 1.27 1.27)
					(thickness 0.15)
				)
			)
		)
		(property "Footprint" ""
			(at 167.64 200.66 0)
			(effects
				(font
					(size 1.27 1.27)
					(thickness 0.15)
				)
				(justify left bottom)
				(hide yes)
			)
		)
		(property "Datasheet" ""
			(at 167.64 205.74 0)
			(effects
				(font
					(size 1.27 1.27)
					(thickness 0.15)
				)
				(justify left bottom)
				(hide yes)
			)
		)
		(property "Description" ""
			(at 158.75 193.04 0)
			(effects
				(font
					(size 1.27 1.27)
				)
				(hide yes)
			)
		)
		(property "Author" "Antmicro"
			(at 167.64 200.66 0)
			(effects
				(font
					(size 1.27 1.27)
					(thickness 0.15)
				)
				(justify left bottom)
				(hide yes)
			)
		)
		(property "License" "Apache-2.0"
			(at 167.64 203.2 0)
			(effects
				(font
					(size 1.27 1.27)
					(thickness 0.15)
				)
				(justify left bottom)
				(hide yes)
			)
		)
		(pin "1"
		)
		(instances
			(project "gmsl-deserializer"
				(path ""
					(reference "#PWR0108")
					(unit 1)
				)
			)
		)
	)
	(symbol
		(lib_id "antmicroTestPoints:TP_0.75mm_SMD")
		(at 323.85 200.66 90)
		(unit 1)
		(exclude_from_sim no)
		(in_bom yes)
		(on_board yes)
		(dnp no)
		(property "Reference" "TP23"
			(at 325.12 197.485 90)
			(effects
				(font
					(size 1.27 1.27)
					(thickness 0.15)
				)
				(justify right)
			)
		)
		(property "Value" "TP_0.75mm_SMD"
			(at 327.66 189.865 0)
			(effects
				(font
					(size 1.27 1.27)
					(thickness 0.15)
				)
				(justify left bottom)
				(hide yes)
			)
		)
		(property "Footprint" "antmicro-footprints:TP_SMD_0.75mm"
			(at 330.2 189.865 0)
			(effects
				(font
					(size 1.27 1.27)
					(thickness 0.15)
				)
				(justify left bottom)
				(hide yes)
			)
		)
		(property "Datasheet" ""
			(at 336.55 182.88 0)
			(effects
				(font
					(size 1.27 1.27)
					(thickness 0.15)
				)
				(justify left bottom)
				(hide yes)
			)
		)
		(property "Description" "SMT test point"
			(at 323.85 200.66 0)
			(effects
				(font
					(size 1.27 1.27)
				)
				(hide yes)
			)
		)
		(property "MPN" ""
			(at 335.28 189.865 0)
			(effects
				(font
					(size 1.27 1.27)
					(thickness 0.15)
				)
				(justify left bottom)
				(hide yes)
			)
		)
		(property "Manufacturer" ""
			(at 330.2 189.865 0)
			(effects
				(font
					(size 1.27 1.27)
					(thickness 0.15)
				)
				(justify left bottom)
				(hide yes)
			)
		)
		(property "Author" "Antmicro"
			(at 332.74 189.865 0)
			(effects
				(font
					(size 1.27 1.27)
					(thickness 0.15)
				)
				(justify left bottom)
				(hide yes)
			)
		)
		(property "License" "Apache-2.0"
			(at 335.28 189.865 0)
			(effects
				(font
					(size 1.27 1.27)
					(thickness 0.15)
				)
				(justify left bottom)
				(hide yes)
			)
		)
		(pin "1"
		)
		(instances
			(project "gmsl-deserializer"
				(path ""
					(reference "TP23")
					(unit 1)
				)
			)
		)
	)
	(symbol
		(lib_id "antmicropower:GND")
		(at 193.04 77.47 0)
		(unit 1)
		(exclude_from_sim no)
		(in_bom yes)
		(on_board yes)
		(dnp no)
		(property "Reference" "#PWR014"
			(at 201.93 80.01 0)
			(effects
				(font
					(size 1.27 1.27)
					(thickness 0.15)
				)
				(justify left bottom)
				(hide yes)
			)
		)
		(property "Value" "GND"
			(at 193.04 81.28 0)
			(effects
				(font
					(size 1.27 1.27)
					(thickness 0.15)
				)
			)
		)
		(property "Footprint" ""
			(at 201.93 85.09 0)
			(effects
				(font
					(size 1.27 1.27)
					(thickness 0.15)
				)
				(justify left bottom)
				(hide yes)
			)
		)
		(property "Datasheet" ""
			(at 201.93 90.17 0)
			(effects
				(font
					(size 1.27 1.27)
					(thickness 0.15)
				)
				(justify left bottom)
				(hide yes)
			)
		)
		(property "Description" ""
			(at 193.04 77.47 0)
			(effects
				(font
					(size 1.27 1.27)
				)
				(hide yes)
			)
		)
		(property "Author" "Antmicro"
			(at 201.93 85.09 0)
			(effects
				(font
					(size 1.27 1.27)
					(thickness 0.15)
				)
				(justify left bottom)
				(hide yes)
			)
		)
		(property "License" "Apache-2.0"
			(at 201.93 87.63 0)
			(effects
				(font
					(size 1.27 1.27)
					(thickness 0.15)
				)
				(justify left bottom)
				(hide yes)
			)
		)
		(pin "1"
		)
		(instances
			(project "gmsl-deserializer"
				(path ""
					(reference "#PWR014")
					(unit 1)
				)
			)
		)
	)
	(symbol
		(lib_id "antmicroTestPoints:TP_0.75mm_SMD")
		(at 53.34 198.12 0)
		(unit 1)
		(exclude_from_sim no)
		(in_bom yes)
		(on_board yes)
		(dnp no)
		(fields_autoplaced yes)
		(property "Reference" "TP1"
			(at 58.42 198.1199 0)
			(effects
				(font
					(size 1.27 1.27)
					(thickness 0.15)
				)
				(justify left)
			)
		)
		(property "Value" "TP_0.75mm_SMD"
			(at 64.135 201.93 0)
			(effects
				(font
					(size 1.27 1.27)
					(thickness 0.15)
				)
				(justify left bottom)
				(hide yes)
			)
		)
		(property "Footprint" "antmicro-footprints:TP_SMD_0.75mm"
			(at 64.135 204.47 0)
			(effects
				(font
					(size 1.27 1.27)
					(thickness 0.15)
				)
				(justify left bottom)
				(hide yes)
			)
		)
		(property "Datasheet" ""
			(at 71.12 210.82 0)
			(effects
				(font
					(size 1.27 1.27)
					(thickness 0.15)
				)
				(justify left bottom)
				(hide yes)
			)
		)
		(property "Description" "SMT test point"
			(at 53.34 198.12 0)
			(effects
				(font
					(size 1.27 1.27)
				)
				(hide yes)
			)
		)
		(property "MPN" ""
			(at 64.135 209.55 0)
			(effects
				(font
					(size 1.27 1.27)
					(thickness 0.15)
				)
				(justify left bottom)
				(hide yes)
			)
		)
		(property "Manufacturer" ""
			(at 64.135 204.47 0)
			(effects
				(font
					(size 1.27 1.27)
					(thickness 0.15)
				)
				(justify left bottom)
				(hide yes)
			)
		)
		(property "Author" "Antmicro"
			(at 64.135 207.01 0)
			(effects
				(font
					(size 1.27 1.27)
					(thickness 0.15)
				)
				(justify left bottom)
				(hide yes)
			)
		)
		(property "License" "Apache-2.0"
			(at 64.135 209.55 0)
			(effects
				(font
					(size 1.27 1.27)
					(thickness 0.15)
				)
				(justify left bottom)
				(hide yes)
			)
		)
		(pin "1"
		)
		(instances
			(project "gmsl-deserializer"
				(path ""
					(reference "TP1")
					(unit 1)
				)
			)
		)
	)
	(symbol
		(lib_id "antmicroCoaxialConnectorsRF:Conn_FAKRA_7-2287906-0")
		(at 153.67 257.81 0)
		(unit 1)
		(exclude_from_sim no)
		(in_bom yes)
		(on_board yes)
		(dnp no)
		(fields_autoplaced yes)
		(property "Reference" "J5"
			(at 162.56 256.8967 0)
			(effects
				(font
					(size 1.27 1.27)
					(thickness 0.15)
				)
				(justify left)
			)
		)
		(property "Value" "Conn_FAKRA_59S2AQ-40MT5-Z_1"
			(at 173.99 265.43 0)
			(effects
				(font
					(size 1.27 1.27)
					(thickness 0.15)
				)
				(justify left bottom)
				(hide yes)
			)
		)
		(property "Footprint" "antmicro-footprints:Conn_FAKRA_7-2287906-0"
			(at 173.99 267.97 0)
			(effects
				(font
					(size 1.27 1.27)
					(thickness 0.15)
				)
				(justify left bottom)
				(hide yes)
			)
		)
		(property "Datasheet" "https://www.te.com/en/product-7-2287906-0.html"
			(at 173.99 270.51 0)
			(effects
				(font
					(size 1.27 1.27)
					(thickness 0.15)
				)
				(justify left bottom)
				(hide yes)
			)
		)
		(property "Description" "FAKRA, 1 POS, ASSY EDGE MOUNT, 12OCLOCK"
			(at 153.67 257.81 0)
			(effects
				(font
					(size 1.27 1.27)
				)
				(hide yes)
			)
		)
		(property "MPN" "7-2287906-0"
			(at 162.56 259.4367 0)
			(effects
				(font
					(size 1.27 1.27)
					(thickness 0.15)
				)
				(justify left)
			)
		)
		(property "Manufacturer" "TE Connectivity"
			(at 173.99 275.59 0)
			(effects
				(font
					(size 1.27 1.27)
					(thickness 0.15)
				)
				(justify left bottom)
				(hide yes)
			)
		)
		(property "Author" "Antmicro"
			(at 173.99 278.13 0)
			(effects
				(font
					(size 1.27 1.27)
					(thickness 0.15)
				)
				(justify left bottom)
				(hide yes)
			)
		)
		(property "License" "Apache-2.0"
			(at 173.99 280.67 0)
			(effects
				(font
					(size 1.27 1.27)
					(thickness 0.15)
				)
				(justify left bottom)
				(hide yes)
			)
		)
		(pin "1"
		)
		(pin "2"
		)
		(pin "3"
		)
		(pin "4"
		)
		(pin "5"
		)
		(instances
			(project "gmsl-deserializer"
				(path ""
					(reference "J5")
					(unit 1)
				)
			)
		)
	)
	(symbol
		(lib_id "antmicropower:GND")
		(at 175.26 121.92 0)
		(unit 1)
		(exclude_from_sim no)
		(in_bom yes)
		(on_board yes)
		(dnp no)
		(property "Reference" "#PWR05"
			(at 184.15 124.46 0)
			(effects
				(font
					(size 1.27 1.27)
					(thickness 0.15)
				)
				(justify left bottom)
				(hide yes)
			)
		)
		(property "Value" "GND"
			(at 175.26 125.73 0)
			(effects
				(font
					(size 1.27 1.27)
					(thickness 0.15)
				)
			)
		)
		(property "Footprint" ""
			(at 184.15 129.54 0)
			(effects
				(font
					(size 1.27 1.27)
					(thickness 0.15)
				)
				(justify left bottom)
				(hide yes)
			)
		)
		(property "Datasheet" ""
			(at 184.15 134.62 0)
			(effects
				(font
					(size 1.27 1.27)
					(thickness 0.15)
				)
				(justify left bottom)
				(hide yes)
			)
		)
		(property "Description" ""
			(at 175.26 121.92 0)
			(effects
				(font
					(size 1.27 1.27)
				)
				(hide yes)
			)
		)
		(property "Author" "Antmicro"
			(at 184.15 129.54 0)
			(effects
				(font
					(size 1.27 1.27)
					(thickness 0.15)
				)
				(justify left bottom)
				(hide yes)
			)
		)
		(property "License" "Apache-2.0"
			(at 184.15 132.08 0)
			(effects
				(font
					(size 1.27 1.27)
					(thickness 0.15)
				)
				(justify left bottom)
				(hide yes)
			)
		)
		(pin "1"
		)
		(instances
			(project "gmsl-deserializer"
				(path ""
					(reference "#PWR05")
					(unit 1)
				)
			)
		)
	)
	(symbol
		(lib_id "antmicropower:GND")
		(at 200.66 63.5 0)
		(unit 1)
		(exclude_from_sim no)
		(in_bom yes)
		(on_board yes)
		(dnp no)
		(property "Reference" "#PWR016"
			(at 209.55 66.04 0)
			(effects
				(font
					(size 1.27 1.27)
					(thickness 0.15)
				)
				(justify left bottom)
				(hide yes)
			)
		)
		(property "Value" "GND"
			(at 200.66 67.31 0)
			(effects
				(font
					(size 1.27 1.27)
					(thickness 0.15)
				)
			)
		)
		(property "Footprint" ""
			(at 209.55 71.12 0)
			(effects
				(font
					(size 1.27 1.27)
					(thickness 0.15)
				)
				(justify left bottom)
				(hide yes)
			)
		)
		(property "Datasheet" ""
			(at 209.55 76.2 0)
			(effects
				(font
					(size 1.27 1.27)
					(thickness 0.15)
				)
				(justify left bottom)
				(hide yes)
			)
		)
		(property "Description" ""
			(at 200.66 63.5 0)
			(effects
				(font
					(size 1.27 1.27)
				)
				(hide yes)
			)
		)
		(property "Author" "Antmicro"
			(at 209.55 71.12 0)
			(effects
				(font
					(size 1.27 1.27)
					(thickness 0.15)
				)
				(justify left bottom)
				(hide yes)
			)
		)
		(property "License" "Apache-2.0"
			(at 209.55 73.66 0)
			(effects
				(font
					(size 1.27 1.27)
					(thickness 0.15)
				)
				(justify left bottom)
				(hide yes)
			)
		)
		(pin "1"
		)
		(instances
			(project "gmsl-deserializer"
				(path ""
					(reference "#PWR016")
					(unit 1)
				)
			)
		)
	)
	(symbol
		(lib_id "antmicropower:GND")
		(at 158.75 217.17 0)
		(unit 1)
		(exclude_from_sim no)
		(in_bom yes)
		(on_board yes)
		(dnp no)
		(property "Reference" "#PWR0105"
			(at 167.64 219.71 0)
			(effects
				(font
					(size 1.27 1.27)
					(thickness 0.15)
				)
				(justify left bottom)
				(hide yes)
			)
		)
		(property "Value" "GND"
			(at 158.75 220.98 0)
			(effects
				(font
					(size 1.27 1.27)
					(thickness 0.15)
				)
			)
		)
		(property "Footprint" ""
			(at 167.64 224.79 0)
			(effects
				(font
					(size 1.27 1.27)
					(thickness 0.15)
				)
				(justify left bottom)
				(hide yes)
			)
		)
		(property "Datasheet" ""
			(at 167.64 229.87 0)
			(effects
				(font
					(size 1.27 1.27)
					(thickness 0.15)
				)
				(justify left bottom)
				(hide yes)
			)
		)
		(property "Description" ""
			(at 158.75 217.17 0)
			(effects
				(font
					(size 1.27 1.27)
				)
				(hide yes)
			)
		)
		(property "Author" "Antmicro"
			(at 167.64 224.79 0)
			(effects
				(font
					(size 1.27 1.27)
					(thickness 0.15)
				)
				(justify left bottom)
				(hide yes)
			)
		)
		(property "License" "Apache-2.0"
			(at 167.64 227.33 0)
			(effects
				(font
					(size 1.27 1.27)
					(thickness 0.15)
				)
				(justify left bottom)
				(hide yes)
			)
		)
		(pin "1"
		)
		(instances
			(project "gmsl-deserializer"
				(path ""
					(reference "#PWR0105")
					(unit 1)
				)
			)
		)
	)
	(symbol
		(lib_id "antmicropower:GND")
		(at 34.29 77.47 0)
		(unit 1)
		(exclude_from_sim no)
		(in_bom yes)
		(on_board yes)
		(dnp no)
		(property "Reference" "#PWR0103"
			(at 43.18 80.01 0)
			(effects
				(font
					(size 1.27 1.27)
					(thickness 0.15)
				)
				(justify left bottom)
				(hide yes)
			)
		)
		(property "Value" "GND"
			(at 34.29 81.28 0)
			(effects
				(font
					(size 1.27 1.27)
					(thickness 0.15)
				)
			)
		)
		(property "Footprint" ""
			(at 43.18 85.09 0)
			(effects
				(font
					(size 1.27 1.27)
					(thickness 0.15)
				)
				(justify left bottom)
				(hide yes)
			)
		)
		(property "Datasheet" ""
			(at 43.18 90.17 0)
			(effects
				(font
					(size 1.27 1.27)
					(thickness 0.15)
				)
				(justify left bottom)
				(hide yes)
			)
		)
		(property "Description" ""
			(at 34.29 77.47 0)
			(effects
				(font
					(size 1.27 1.27)
				)
				(hide yes)
			)
		)
		(property "Author" "Antmicro"
			(at 43.18 85.09 0)
			(effects
				(font
					(size 1.27 1.27)
					(thickness 0.15)
				)
				(justify left bottom)
				(hide yes)
			)
		)
		(property "License" "Apache-2.0"
			(at 43.18 87.63 0)
			(effects
				(font
					(size 1.27 1.27)
					(thickness 0.15)
				)
				(justify left bottom)
				(hide yes)
			)
		)
		(pin "1"
		)
		(instances
			(project "gmsl-deserializer"
				(path ""
					(reference "#PWR0103")
					(unit 1)
				)
			)
		)
	)
	(symbol
		(lib_id "antmicroTVSDiodes:SMF4L15A")
		(at 55.88 71.12 270)
		(unit 1)
		(exclude_from_sim no)
		(in_bom yes)
		(on_board yes)
		(dnp no)
		(property "Reference" "D1"
			(at 58.42 72.39 90)
			(effects
				(font
					(size 1.27 1.27)
					(thickness 0.15)
				)
				(justify left)
			)
		)
		(property "Value" "SMF4L15A"
			(at 58.42 74.93 90)
			(effects
				(font
					(size 1.27 1.27)
					(thickness 0.15)
				)
				(justify left)
			)
		)
		(property "Footprint" "antmicro-footprints:SOD-123FL"
			(at 45.72 97.79 0)
			(effects
				(font
					(size 1.27 1.27)
					(thickness 0.15)
				)
				(justify left bottom)
				(hide yes)
			)
		)
		(property "Datasheet" "https://www.littelfuse.com/media?resourcetype=datasheets&itemid=d2ba8fab-1de3-4176-8530-f36ecb0b8799&filename=smf4l"
			(at 43.18 97.79 0)
			(effects
				(font
					(size 1.27 1.27)
					(thickness 0.15)
				)
				(justify left bottom)
				(hide yes)
			)
		)
		(property "Description" "Unidirectional TVS, 30 kV,  SOD-123FL, 15 V, 600 pF"
			(at 55.88 71.12 0)
			(effects
				(font
					(size 1.27 1.27)
				)
				(hide yes)
			)
		)
		(property "MPN" "SMF4L15A"
			(at 40.64 97.79 0)
			(effects
				(font
					(size 1.27 1.27)
					(thickness 0.15)
				)
				(justify left bottom)
				(hide yes)
			)
		)
		(property "Manufacturer" "Littelfuse"
			(at 38.1 97.79 0)
			(effects
				(font
					(size 1.27 1.27)
					(thickness 0.15)
				)
				(justify left bottom)
				(hide yes)
			)
		)
		(property "Author" "Antmicro"
			(at 35.56 97.79 0)
			(effects
				(font
					(size 1.27 1.27)
					(thickness 0.15)
				)
				(justify left bottom)
				(hide yes)
			)
		)
		(property "License" "Apache-2.0"
			(at 33.02 97.79 0)
			(effects
				(font
					(size 1.27 1.27)
					(thickness 0.15)
				)
				(justify left bottom)
				(hide yes)
			)
		)
		(pin "1"
		)
		(pin "2"
		)
		(instances
			(project "gmsl-deserializer"
				(path ""
					(reference "D1")
					(unit 1)
				)
			)
		)
	)
	(symbol
		(lib_id "antmicroLEDIndicationDiscrete:LED_G_0603_LTST-C190GKT")
		(at 66.04 102.87 270)
		(mirror x)
		(unit 1)
		(exclude_from_sim no)
		(in_bom yes)
		(on_board yes)
		(dnp no)
		(property "Reference" "D2"
			(at 69.85 99.06 90)
			(effects
				(font
					(size 1.27 1.27)
					(thickness 0.15)
				)
				(justify left)
			)
		)
		(property "Value" "LED_G_0603_LTST-C190GKT"
			(at 37.465 97.79 90)
			(effects
				(font
					(size 1.27 1.27)
					(thickness 0.15)
				)
				(justify left)
				(hide yes)
			)
		)
		(property "Footprint" "antmicro-footprints:LED_0603_1608Metric_G"
			(at 55.88 80.01 0)
			(effects
				(font
					(size 1.27 1.27)
					(thickness 0.15)
				)
				(justify left bottom)
				(hide yes)
			)
		)
		(property "Datasheet" "https://media.digikey.com/pdf/Data%20Sheets/Lite-On%20PDFs/LTST-C190GKT.pdf"
			(at 53.34 80.01 0)
			(effects
				(font
					(size 1.27 1.27)
					(thickness 0.15)
				)
				(justify left bottom)
				(hide yes)
			)
		)
		(property "Description" "LED, Green, SMD, 0603, 20 mA, 2.1 V, 569 nm"
			(at 66.04 102.87 0)
			(effects
				(font
					(size 1.27 1.27)
				)
				(hide yes)
			)
		)
		(property "MPN" "LTST-C190GKT"
			(at 69.85 100.33 90)
			(effects
				(font
					(size 1.27 1.27)
					(thickness 0.15)
				)
				(justify left bottom)
			)
		)
		(property "Manufacturer" "Lite-On"
			(at 48.26 80.01 0)
			(effects
				(font
					(size 1.27 1.27)
					(thickness 0.15)
				)
				(justify left bottom)
				(hide yes)
			)
		)
		(property "Author" "Antmicro"
			(at 45.72 80.01 0)
			(effects
				(font
					(size 1.27 1.27)
					(thickness 0.15)
				)
				(justify left bottom)
				(hide yes)
			)
		)
		(property "License" "Apache-2.0"
			(at 43.18 80.01 0)
			(effects
				(font
					(size 1.27 1.27)
					(thickness 0.15)
				)
				(justify left bottom)
				(hide yes)
			)
		)
		(property "VSD_class" "LED"
			(at 40.64 80.01 0)
			(effects
				(font
					(size 1.27 1.27)
				)
				(justify left bottom)
				(hide yes)
			)
		)
		(property "Color" "Green"
			(at 60.96 80.01 0)
			(effects
				(font
					(size 1.27 1.27)
				)
				(justify left bottom)
				(hide yes)
			)
		)
		(pin "1"
		)
		(pin "2"
		)
		(instances
			(project "gmsl-deserializer"
				(path ""
					(reference "D2")
					(unit 1)
				)
			)
		)
	)
	(symbol
		(lib_id "antmicroTestPoints:TP_0.75mm_SMD")
		(at 53.34 203.2 0)
		(unit 1)
		(exclude_from_sim no)
		(in_bom yes)
		(on_board yes)
		(dnp no)
		(fields_autoplaced yes)
		(property "Reference" "TP3"
			(at 58.42 203.1999 0)
			(effects
				(font
					(size 1.27 1.27)
					(thickness 0.15)
				)
				(justify left)
			)
		)
		(property "Value" "TP_0.75mm_SMD"
			(at 64.135 207.01 0)
			(effects
				(font
					(size 1.27 1.27)
					(thickness 0.15)
				)
				(justify left bottom)
				(hide yes)
			)
		)
		(property "Footprint" "antmicro-footprints:TP_SMD_0.75mm"
			(at 64.135 209.55 0)
			(effects
				(font
					(size 1.27 1.27)
					(thickness 0.15)
				)
				(justify left bottom)
				(hide yes)
			)
		)
		(property "Datasheet" ""
			(at 71.12 215.9 0)
			(effects
				(font
					(size 1.27 1.27)
					(thickness 0.15)
				)
				(justify left bottom)
				(hide yes)
			)
		)
		(property "Description" "SMT test point"
			(at 53.34 203.2 0)
			(effects
				(font
					(size 1.27 1.27)
				)
				(hide yes)
			)
		)
		(property "MPN" ""
			(at 64.135 214.63 0)
			(effects
				(font
					(size 1.27 1.27)
					(thickness 0.15)
				)
				(justify left bottom)
				(hide yes)
			)
		)
		(property "Manufacturer" ""
			(at 64.135 209.55 0)
			(effects
				(font
					(size 1.27 1.27)
					(thickness 0.15)
				)
				(justify left bottom)
				(hide yes)
			)
		)
		(property "Author" "Antmicro"
			(at 64.135 212.09 0)
			(effects
				(font
					(size 1.27 1.27)
					(thickness 0.15)
				)
				(justify left bottom)
				(hide yes)
			)
		)
		(property "License" "Apache-2.0"
			(at 64.135 214.63 0)
			(effects
				(font
					(size 1.27 1.27)
					(thickness 0.15)
				)
				(justify left bottom)
				(hide yes)
			)
		)
		(pin "1"
		)
		(instances
			(project "gmsl-deserializer"
				(path ""
					(reference "TP3")
					(unit 1)
				)
			)
		)
	)
	(symbol
		(lib_id "antmicropower:+1V8")
		(at 146.05 55.88 0)
		(unit 1)
		(exclude_from_sim no)
		(in_bom yes)
		(on_board yes)
		(dnp no)
		(property "Reference" "#PWR011"
			(at 161.29 58.42 0)
			(effects
				(font
					(size 1.27 1.27)
					(thickness 0.15)
				)
				(justify left bottom)
				(hide yes)
			)
		)
		(property "Value" "+1V8"
			(at 146.05 52.07 0)
			(effects
				(font
					(size 1.27 1.27)
					(thickness 0.15)
				)
			)
		)
		(property "Footprint" ""
			(at 161.29 63.5 0)
			(effects
				(font
					(size 1.27 1.27)
					(thickness 0.15)
				)
				(justify left bottom)
				(hide yes)
			)
		)
		(property "Datasheet" ""
			(at 161.29 66.04 0)
			(effects
				(font
					(size 1.27 1.27)
					(thickness 0.15)
				)
				(justify left bottom)
				(hide yes)
			)
		)
		(property "Description" ""
			(at 146.05 55.88 0)
			(effects
				(font
					(size 1.27 1.27)
				)
				(hide yes)
			)
		)
		(property "Author" "Antmicro"
			(at 161.29 63.5 0)
			(effects
				(font
					(size 1.27 1.27)
					(thickness 0.15)
				)
				(justify left bottom)
				(hide yes)
			)
		)
		(property "License" "Apache-2.0"
			(at 161.29 66.04 0)
			(effects
				(font
					(size 1.27 1.27)
					(thickness 0.15)
				)
				(justify left bottom)
				(hide yes)
			)
		)
		(pin "1"
		)
		(instances
			(project "gmsl-deserializer"
				(path ""
					(reference "#PWR011")
					(unit 1)
				)
			)
		)
	)
	(symbol
		(lib_id "antmicroResistors0402:R_100R_0402")
		(at 114.3 139.7 0)
		(unit 1)
		(exclude_from_sim no)
		(in_bom no)
		(on_board yes)
		(dnp yes)
		(property "Reference" "R68"
			(at 114.3 138.43 0)
			(effects
				(font
					(size 1.27 1.27)
					(thickness 0.15)
				)
				(justify right)
			)
		)
		(property "Value" "R_100R_0402"
			(at 134.62 152.4 0)
			(effects
				(font
					(size 1.27 1.27)
					(thickness 0.15)
				)
				(justify left bottom)
				(hide yes)
			)
		)
		(property "Footprint" "antmicro-footprints:R_0402_1005Metric"
			(at 134.62 154.94 0)
			(effects
				(font
					(size 1.27 1.27)
					(thickness 0.15)
				)
				(justify left bottom)
				(hide yes)
			)
		)
		(property "Datasheet" "https://www.bourns.com/docs/product-datasheets/cr.pdf"
			(at 134.62 157.48 0)
			(effects
				(font
					(size 1.27 1.27)
					(thickness 0.15)
				)
				(justify left bottom)
				(hide yes)
			)
		)
		(property "Description" "SMD Chip Resistor, 100 ohm, ± 1%, 62.5 mW, 0402 [1005 Metric], Thick Film, General Purpose"
			(at 114.3 139.7 0)
			(effects
				(font
					(size 1.27 1.27)
				)
				(hide yes)
			)
		)
		(property "MPN" "CR0402-FX-1000GLF"
			(at 134.62 160.02 0)
			(effects
				(font
					(size 1.27 1.27)
					(thickness 0.15)
				)
				(justify left bottom)
				(hide yes)
			)
		)
		(property "Manufacturer" "Bourns"
			(at 134.62 162.56 0)
			(effects
				(font
					(size 1.27 1.27)
					(thickness 0.15)
				)
				(justify left bottom)
				(hide yes)
			)
		)
		(property "License" "Apache-2.0"
			(at 134.62 165.1 0)
			(effects
				(font
					(size 1.27 1.27)
					(thickness 0.15)
				)
				(justify left bottom)
				(hide yes)
			)
		)
		(property "Author" "Antmicro"
			(at 134.62 167.64 0)
			(effects
				(font
					(size 1.27 1.27)
					(thickness 0.15)
				)
				(justify left bottom)
				(hide yes)
			)
		)
		(property "Val" "100R"
			(at 121.92 138.43 0)
			(effects
				(font
					(size 1.27 1.27)
					(thickness 0.15)
				)
			)
		)
		(property "Tolerance" "1%"
			(at 134.62 149.86 0)
			(effects
				(font
					(size 1.27 1.27)
				)
				(justify left bottom)
				(hide yes)
			)
		)
		(pin "1"
		)
		(pin "2"
		)
		(instances
			(project "gmsl-deserializer"
				(path ""
					(reference "R68")
					(unit 1)
				)
			)
		)
	)
	(symbol
		(lib_id "antmicroResistors0402:R_100R_0402")
		(at 318.77 175.26 0)
		(unit 1)
		(exclude_from_sim no)
		(in_bom yes)
		(on_board yes)
		(dnp no)
		(property "Reference" "R11"
			(at 319.405 173.99 0)
			(effects
				(font
					(size 1.27 1.27)
					(thickness 0.15)
				)
				(justify right)
			)
		)
		(property "Value" "R_100R_0402"
			(at 339.09 187.96 0)
			(effects
				(font
					(size 1.27 1.27)
					(thickness 0.15)
				)
				(justify left bottom)
				(hide yes)
			)
		)
		(property "Footprint" "antmicro-footprints:R_0402_1005Metric"
			(at 339.09 190.5 0)
			(effects
				(font
					(size 1.27 1.27)
					(thickness 0.15)
				)
				(justify left bottom)
				(hide yes)
			)
		)
		(property "Datasheet" "https://www.bourns.com/docs/product-datasheets/cr.pdf"
			(at 339.09 193.04 0)
			(effects
				(font
					(size 1.27 1.27)
					(thickness 0.15)
				)
				(justify left bottom)
				(hide yes)
			)
		)
		(property "Description" "SMD Chip Resistor, 100 ohm, ± 1%, 62.5 mW, 0402 [1005 Metric], Thick Film, General Purpose"
			(at 318.77 175.26 0)
			(effects
				(font
					(size 1.27 1.27)
				)
				(hide yes)
			)
		)
		(property "MPN" "CR0402-FX-1000GLF"
			(at 339.09 195.58 0)
			(effects
				(font
					(size 1.27 1.27)
					(thickness 0.15)
				)
				(justify left bottom)
				(hide yes)
			)
		)
		(property "Manufacturer" "Bourns"
			(at 339.09 198.12 0)
			(effects
				(font
					(size 1.27 1.27)
					(thickness 0.15)
				)
				(justify left bottom)
				(hide yes)
			)
		)
		(property "License" "Apache-2.0"
			(at 339.09 200.66 0)
			(effects
				(font
					(size 1.27 1.27)
					(thickness 0.15)
				)
				(justify left bottom)
				(hide yes)
			)
		)
		(property "Author" "Antmicro"
			(at 339.09 203.2 0)
			(effects
				(font
					(size 1.27 1.27)
					(thickness 0.15)
				)
				(justify left bottom)
				(hide yes)
			)
		)
		(property "Val" "100R"
			(at 325.755 173.99 0)
			(effects
				(font
					(size 1.27 1.27)
					(thickness 0.15)
				)
			)
		)
		(property "Tolerance" "1%"
			(at 339.09 185.42 0)
			(effects
				(font
					(size 1.27 1.27)
				)
				(justify left bottom)
				(hide yes)
			)
		)
		(pin "1"
		)
		(pin "2"
		)
		(instances
			(project "gmsl-deserializer"
				(path ""
					(reference "R11")
					(unit 1)
				)
			)
		)
	)
	(symbol
		(lib_id "antmicroCapacitors0402:C_100n_0402")
		(at 45.72 76.2 90)
		(unit 1)
		(exclude_from_sim no)
		(in_bom yes)
		(on_board yes)
		(dnp no)
		(property "Reference" "C2"
			(at 47.625 72.39 90)
			(effects
				(font
					(size 1.27 1.27)
					(thickness 0.15)
				)
				(justify right)
			)
		)
		(property "Value" "C_100n_0402"
			(at 55.88 55.88 0)
			(effects
				(font
					(size 1.27 1.27)
					(thickness 0.15)
				)
				(justify left bottom)
				(hide yes)
			)
		)
		(property "Footprint" "antmicro-footprints:C_0402_1005Metric"
			(at 58.42 55.88 0)
			(effects
				(font
					(size 1.27 1.27)
					(thickness 0.15)
				)
				(justify left bottom)
				(hide yes)
			)
		)
		(property "Datasheet" "https://www.murata.com/products/productdetail?partno=GRM155R61H104KE14%23"
			(at 60.96 55.88 0)
			(effects
				(font
					(size 1.27 1.27)
					(thickness 0.15)
				)
				(justify left bottom)
				(hide yes)
			)
		)
		(property "Description" "SMD Multilayer Ceramic Capacitor, 0.1 µF, 50 V, 0402 [1005 Metric], ± 10%, X5R, GRM Series"
			(at 45.72 76.2 0)
			(effects
				(font
					(size 1.27 1.27)
				)
				(hide yes)
			)
		)
		(property "MPN" "GRM155R61H104KE14D"
			(at 63.5 55.88 0)
			(effects
				(font
					(size 1.27 1.27)
					(thickness 0.15)
				)
				(justify left bottom)
				(hide yes)
			)
		)
		(property "Manufacturer" "Murata"
			(at 66.04 55.88 0)
			(effects
				(font
					(size 1.27 1.27)
					(thickness 0.15)
				)
				(justify left bottom)
				(hide yes)
			)
		)
		(property "License" "Apache-2.0"
			(at 68.58 55.88 0)
			(effects
				(font
					(size 1.27 1.27)
					(thickness 0.15)
				)
				(justify left bottom)
				(hide yes)
			)
		)
		(property "Author" "Antmicro"
			(at 71.12 55.88 0)
			(effects
				(font
					(size 1.27 1.27)
					(thickness 0.15)
				)
				(justify left bottom)
				(hide yes)
			)
		)
		(property "Val" "100n"
			(at 46.99 75.565 90)
			(effects
				(font
					(size 1.27 1.27)
					(thickness 0.15)
				)
				(justify right)
			)
		)
		(property "Voltage" "50V"
			(at 73.66 55.88 0)
			(effects
				(font
					(size 1.27 1.27)
				)
				(justify left bottom)
				(hide yes)
			)
		)
		(property "Dielectric" "X5R"
			(at 76.2 55.88 0)
			(effects
				(font
					(size 1.27 1.27)
				)
				(justify left bottom)
				(hide yes)
			)
		)
		(pin "1"
		)
		(pin "2"
		)
		(instances
			(project "gmsl-deserializer"
				(path ""
					(reference "C2")
					(unit 1)
				)
			)
		)
	)
	(symbol
		(lib_id "antmicroWire2BoardConnectors:Molex_Nano-Fit_1x2_SMD_1054301202")
		(at 26.67 69.85 0)
		(mirror y)
		(unit 1)
		(exclude_from_sim no)
		(in_bom yes)
		(on_board yes)
		(dnp no)
		(fields_autoplaced yes)
		(property "Reference" "J1"
			(at 22.225 62.23 0)
			(effects
				(font
					(size 1.27 1.27)
					(thickness 0.15)
				)
			)
		)
		(property "Value" "Molex_Nano-Fit_1x2_SMD_1054301202"
			(at 0 77.47 0)
			(effects
				(font
					(size 1.27 1.27)
					(thickness 0.15)
				)
				(justify left bottom)
				(hide yes)
			)
		)
		(property "Footprint" "antmicro-footprints:Conn_Molex_Nano-Fit_1x2_SMD_1054301202"
			(at 0 80.01 0)
			(effects
				(font
					(size 1.27 1.27)
					(thickness 0.15)
				)
				(justify left bottom)
				(hide yes)
			)
		)
		(property "Datasheet" "https://www.farnell.com/cad/3578051.pdf"
			(at 0 82.55 0)
			(effects
				(font
					(size 1.27 1.27)
					(thickness 0.15)
				)
				(justify left bottom)
				(hide yes)
			)
		)
		(property "Description" "Pin Header, Pitch 2.5 mm, 1 Row, 2 Contacts, Nano-Fit"
			(at 26.67 69.85 0)
			(effects
				(font
					(size 1.27 1.27)
				)
				(hide yes)
			)
		)
		(property "Manufacturer" "Molex"
			(at 0 85.09 0)
			(effects
				(font
					(size 1.27 1.27)
					(thickness 0.15)
				)
				(justify left bottom)
				(hide yes)
			)
		)
		(property "MPN" "105430-1202"
			(at 22.225 64.77 0)
			(effects
				(font
					(size 1.27 1.27)
					(thickness 0.15)
				)
			)
		)
		(property "Author" "Antmicro"
			(at 0 87.63 0)
			(effects
				(font
					(size 1.27 1.27)
					(thickness 0.15)
				)
				(justify left bottom)
				(hide yes)
			)
		)
		(property "License" "Apache-2.0"
			(at 0 90.17 0)
			(effects
				(font
					(size 1.27 1.27)
					(thickness 0.15)
				)
				(justify left bottom)
				(hide yes)
			)
		)
		(pin "1"
		)
		(pin "2"
		)
		(pin "MP"
		)
		(instances
			(project "gmsl-deserializer"
				(path ""
					(reference "J1")
					(unit 1)
				)
			)
		)
	)
	(symbol
		(lib_id "antmicroResistors0402:R_100R_0402")
		(at 298.45 157.48 0)
		(unit 1)
		(exclude_from_sim no)
		(in_bom yes)
		(on_board yes)
		(dnp no)
		(property "Reference" "R9"
			(at 298.45 156.21 0)
			(effects
				(font
					(size 1.27 1.27)
					(thickness 0.15)
				)
				(justify right)
			)
		)
		(property "Value" "R_100R_0402"
			(at 318.77 170.18 0)
			(effects
				(font
					(size 1.27 1.27)
					(thickness 0.15)
				)
				(justify left bottom)
				(hide yes)
			)
		)
		(property "Footprint" "antmicro-footprints:R_0402_1005Metric"
			(at 318.77 172.72 0)
			(effects
				(font
					(size 1.27 1.27)
					(thickness 0.15)
				)
				(justify left bottom)
				(hide yes)
			)
		)
		(property "Datasheet" "https://www.bourns.com/docs/product-datasheets/cr.pdf"
			(at 318.77 175.26 0)
			(effects
				(font
					(size 1.27 1.27)
					(thickness 0.15)
				)
				(justify left bottom)
				(hide yes)
			)
		)
		(property "Description" "SMD Chip Resistor, 100 ohm, ± 1%, 62.5 mW, 0402 [1005 Metric], Thick Film, General Purpose"
			(at 298.45 157.48 0)
			(effects
				(font
					(size 1.27 1.27)
				)
				(hide yes)
			)
		)
		(property "MPN" "CR0402-FX-1000GLF"
			(at 318.77 177.8 0)
			(effects
				(font
					(size 1.27 1.27)
					(thickness 0.15)
				)
				(justify left bottom)
				(hide yes)
			)
		)
		(property "Manufacturer" "Bourns"
			(at 318.77 180.34 0)
			(effects
				(font
					(size 1.27 1.27)
					(thickness 0.15)
				)
				(justify left bottom)
				(hide yes)
			)
		)
		(property "License" "Apache-2.0"
			(at 318.77 182.88 0)
			(effects
				(font
					(size 1.27 1.27)
					(thickness 0.15)
				)
				(justify left bottom)
				(hide yes)
			)
		)
		(property "Author" "Antmicro"
			(at 318.77 185.42 0)
			(effects
				(font
					(size 1.27 1.27)
					(thickness 0.15)
				)
				(justify left bottom)
				(hide yes)
			)
		)
		(property "Val" "100R"
			(at 306.07 156.21 0)
			(effects
				(font
					(size 1.27 1.27)
					(thickness 0.15)
				)
			)
		)
		(property "Tolerance" "1%"
			(at 318.77 167.64 0)
			(effects
				(font
					(size 1.27 1.27)
				)
				(justify left bottom)
				(hide yes)
			)
		)
		(pin "1"
		)
		(pin "2"
		)
		(instances
			(project "gmsl-deserializer"
				(path ""
					(reference "R9")
					(unit 1)
				)
			)
		)
	)
	(symbol
		(lib_id "antmicroFCCConnectors:Conn_FFC_WE_68715014522")
		(at 351.79 78.74 0)
		(unit 1)
		(exclude_from_sim no)
		(in_bom yes)
		(on_board yes)
		(dnp no)
		(fields_autoplaced yes)
		(property "Reference" "J6"
			(at 361.315 142.8749 0)
			(effects
				(font
					(size 1.27 1.27)
					(thickness 0.15)
				)
				(justify left)
			)
		)
		(property "Value" "Conn_FFC_WE_68715014522"
			(at 361.315 145.4149 0)
			(effects
				(font
					(size 1.27 1.27)
					(thickness 0.15)
				)
				(justify left)
			)
		)
		(property "Footprint" "antmicro-footprints:Conn_FFC_WE_68715014x22"
			(at 370.84 88.9 0)
			(effects
				(font
					(size 1.27 1.27)
					(thickness 0.15)
				)
				(justify left bottom)
				(hide yes)
			)
		)
		(property "Datasheet" "https://www.we-online.com/components/products/datasheet/68715014522.pdf"
			(at 370.84 91.44 0)
			(effects
				(font
					(size 1.27 1.27)
					(thickness 0.15)
				)
				(justify left bottom)
				(hide yes)
			)
		)
		(property "Description" "FFC connector"
			(at 351.79 78.74 0)
			(effects
				(font
					(size 1.27 1.27)
				)
				(hide yes)
			)
		)
		(property "MPN" "68715014522"
			(at 370.84 93.98 0)
			(effects
				(font
					(size 1.27 1.27)
					(thickness 0.15)
				)
				(justify left bottom)
				(hide yes)
			)
		)
		(property "Manufacturer" "Würth Elektronik"
			(at 370.84 96.52 0)
			(effects
				(font
					(size 1.27 1.27)
					(thickness 0.15)
				)
				(justify left bottom)
				(hide yes)
			)
		)
		(property "Author" "Antmicro"
			(at 370.84 99.06 0)
			(effects
				(font
					(size 1.27 1.27)
					(thickness 0.15)
				)
				(justify left bottom)
				(hide yes)
			)
		)
		(property "License" "Apache-2.0"
			(at 370.84 101.6 0)
			(effects
				(font
					(size 1.27 1.27)
					(thickness 0.15)
				)
				(justify left bottom)
				(hide yes)
			)
		)
		(property "VSD_Class" "Antmicro Dual Camera interface"
			(at 370.84 101.6 0)
			(effects
				(font
					(size 1.27 1.27)
				)
				(justify left top)
				(hide yes)
			)
		)
		(pin "1"
		)
		(pin "10"
		)
		(pin "11"
		)
		(pin "12"
		)
		(pin "13"
		)
		(pin "14"
		)
		(pin "15"
		)
		(pin "16"
		)
		(pin "17"
		)
		(pin "18"
		)
		(pin "19"
		)
		(pin "2"
		)
		(pin "20"
		)
		(pin "21"
		)
		(pin "22"
		)
		(pin "23"
		)
		(pin "24"
		)
		(pin "25"
		)
		(pin "26"
		)
		(pin "27"
		)
		(pin "28"
		)
		(pin "29"
		)
		(pin "3"
		)
		(pin "30"
		)
		(pin "31"
		)
		(pin "32"
		)
		(pin "33"
		)
		(pin "34"
		)
		(pin "35"
		)
		(pin "36"
		)
		(pin "37"
		)
		(pin "38"
		)
		(pin "39"
		)
		(pin "4"
		)
		(pin "40"
		)
		(pin "41"
		)
		(pin "42"
		)
		(pin "43"
		)
		(pin "44"
		)
		(pin "45"
		)
		(pin "46"
		)
		(pin "47"
		)
		(pin "48"
		)
		(pin "49"
		)
		(pin "5"
		)
		(pin "50"
		)
		(pin "6"
		)
		(pin "7"
		)
		(pin "8"
		)
		(pin "9"
		)
		(pin "MP1"
		)
		(pin "MP2"
		)
		(instances
			(project "gmsl-deserializer"
				(path ""
					(reference "J6")
					(unit 1)
				)
			)
		)
	)
	(symbol
		(lib_id "antmicroLogicTranslatorsLevelShifters:NTS0102_TSSOP")
		(at 144.78 129.54 0)
		(unit 1)
		(exclude_from_sim no)
		(in_bom yes)
		(on_board yes)
		(dnp no)
		(fields_autoplaced yes)
		(property "Reference" "U8"
			(at 154.94 121.92 0)
			(effects
				(font
					(size 1.27 1.27)
					(thickness 0.15)
				)
			)
		)
		(property "Value" "NTS0102_TSSOP"
			(at 154.94 124.46 0)
			(effects
				(font
					(size 1.27 1.27)
					(thickness 0.15)
				)
			)
		)
		(property "Footprint" "antmicro-footprints:TSSOP-8_3x3mm_P0.65mm"
			(at 180.34 138.43 0)
			(effects
				(font
					(size 1.27 1.27)
					(thickness 0.15)
				)
				(justify left bottom)
				(hide yes)
			)
		)
		(property "Datasheet" "https://www.mouser.com/datasheet/2/302/NTS0102-1127324.pdf"
			(at 180.34 140.97 0)
			(effects
				(font
					(size 1.27 1.27)
					(thickness 0.15)
				)
				(justify left bottom)
				(hide yes)
			)
		)
		(property "Description" "Transceiver, 1.65 V to 3.6 V, TSSOP-8"
			(at 144.78 129.54 0)
			(effects
				(font
					(size 1.27 1.27)
				)
				(hide yes)
			)
		)
		(property "MPN" "NTS0102DP"
			(at 180.34 143.51 0)
			(effects
				(font
					(size 1.27 1.27)
					(thickness 0.15)
				)
				(justify left bottom)
				(hide yes)
			)
		)
		(property "Manufacturer" "NXP"
			(at 180.34 146.05 0)
			(effects
				(font
					(size 1.27 1.27)
					(thickness 0.15)
				)
				(justify left bottom)
				(hide yes)
			)
		)
		(property "Author" "Antmicro"
			(at 180.34 148.59 0)
			(effects
				(font
					(size 1.27 1.27)
					(thickness 0.15)
				)
				(justify left bottom)
				(hide yes)
			)
		)
		(property "License" "Apache-2.0"
			(at 180.34 151.13 0)
			(effects
				(font
					(size 1.27 1.27)
					(thickness 0.15)
				)
				(justify left bottom)
				(hide yes)
			)
		)
		(pin "1"
		)
		(pin "2"
		)
		(pin "3"
		)
		(pin "4"
		)
		(pin "5"
		)
		(pin "6"
		)
		(pin "7"
		)
		(pin "8"
		)
		(instances
			(project "gmsl-deserializer"
				(path ""
					(reference "U8")
					(unit 1)
				)
			)
		)
	)
	(symbol
		(lib_id "antmicropower:+5V")
		(at 41.91 222.25 0)
		(unit 1)
		(exclude_from_sim no)
		(in_bom yes)
		(on_board yes)
		(dnp no)
		(property "Reference" "#PWR0121"
			(at 57.15 224.79 0)
			(effects
				(font
					(size 1.27 1.27)
					(thickness 0.15)
				)
				(justify left bottom)
				(hide yes)
			)
		)
		(property "Value" "+5V"
			(at 41.91 218.44 0)
			(effects
				(font
					(size 1.27 1.27)
					(thickness 0.15)
				)
			)
		)
		(property "Footprint" ""
			(at 57.15 229.87 0)
			(effects
				(font
					(size 1.27 1.27)
					(thickness 0.15)
				)
				(justify left bottom)
				(hide yes)
			)
		)
		(property "Datasheet" ""
			(at 57.15 232.41 0)
			(effects
				(font
					(size 1.27 1.27)
					(thickness 0.15)
				)
				(justify left bottom)
				(hide yes)
			)
		)
		(property "Description" ""
			(at 41.91 222.25 0)
			(effects
				(font
					(size 1.27 1.27)
				)
				(hide yes)
			)
		)
		(property "Author" "Antmicro"
			(at 57.15 229.87 0)
			(effects
				(font
					(size 1.27 1.27)
					(thickness 0.15)
				)
				(justify left bottom)
				(hide yes)
			)
		)
		(property "License" "Apache-2.0"
			(at 57.15 232.41 0)
			(effects
				(font
					(size 1.27 1.27)
					(thickness 0.15)
				)
				(justify left bottom)
				(hide yes)
			)
		)
		(pin "1"
		)
		(instances
			(project "gmsl-deserializer"
				(path ""
					(reference "#PWR0121")
					(unit 1)
				)
			)
		)
	)
	(symbol
		(lib_id "antmicroResistors0402:R_10k_0402")
		(at 120.65 78.74 90)
		(unit 1)
		(exclude_from_sim no)
		(in_bom yes)
		(on_board yes)
		(dnp no)
		(fields_autoplaced yes)
		(property "Reference" "R1"
			(at 122.555 74.9299 90)
			(effects
				(font
					(size 1.27 1.27)
					(thickness 0.15)
				)
				(justify right)
			)
		)
		(property "Value" "R_10k_0402"
			(at 133.35 58.42 0)
			(effects
				(font
					(size 1.27 1.27)
					(thickness 0.15)
				)
				(justify left bottom)
				(hide yes)
			)
		)
		(property "Footprint" "antmicro-footprints:R_0402_1005Metric"
			(at 135.89 58.42 0)
			(effects
				(font
					(size 1.27 1.27)
					(thickness 0.15)
				)
				(justify left bottom)
				(hide yes)
			)
		)
		(property "Datasheet" "https://www.bourns.com/docs/product-datasheets/cr.pdf"
			(at 138.43 58.42 0)
			(effects
				(font
					(size 1.27 1.27)
					(thickness 0.15)
				)
				(justify left bottom)
				(hide yes)
			)
		)
		(property "Description" "SMD Chip Resistor, 10 kohm, ± 1%, 62.5 mW, 0402 [1005 Metric], Thick Film, General Purpose"
			(at 120.65 78.74 0)
			(effects
				(font
					(size 1.27 1.27)
				)
				(hide yes)
			)
		)
		(property "MPN" "CR0402-FX-1002GLF"
			(at 140.97 58.42 0)
			(effects
				(font
					(size 1.27 1.27)
					(thickness 0.15)
				)
				(justify left bottom)
				(hide yes)
			)
		)
		(property "Manufacturer" "Bourns"
			(at 143.51 58.42 0)
			(effects
				(font
					(size 1.27 1.27)
					(thickness 0.15)
				)
				(justify left bottom)
				(hide yes)
			)
		)
		(property "License" "Apache-2.0"
			(at 146.05 58.42 0)
			(effects
				(font
					(size 1.27 1.27)
					(thickness 0.15)
				)
				(justify left bottom)
				(hide yes)
			)
		)
		(property "Author" "Antmicro"
			(at 148.59 58.42 0)
			(effects
				(font
					(size 1.27 1.27)
					(thickness 0.15)
				)
				(justify left bottom)
				(hide yes)
			)
		)
		(property "Val" "10k"
			(at 122.555 77.4699 90)
			(effects
				(font
					(size 1.27 1.27)
					(thickness 0.15)
				)
				(justify right)
			)
		)
		(property "Tolerance" "1%"
			(at 130.81 58.42 0)
			(effects
				(font
					(size 1.27 1.27)
				)
				(justify left bottom)
				(hide yes)
			)
		)
		(pin "1"
		)
		(pin "2"
		)
		(instances
			(project "gmsl-deserializer"
				(path ""
					(reference "R1")
					(unit 1)
				)
			)
		)
	)
	(symbol
		(lib_id "antmicropower:PWR_FLAG")
		(at 335.28 195.58 0)
		(unit 1)
		(exclude_from_sim no)
		(in_bom yes)
		(on_board yes)
		(dnp no)
		(property "Reference" "#FLG0101"
			(at 335.28 193.675 0)
			(effects
				(font
					(size 1.27 1.27)
				)
				(hide yes)
			)
		)
		(property "Value" "PWR_FLAG"
			(at 335.28 191.77 0)
			(effects
				(font
					(size 1.27 1.27)
				)
			)
		)
		(property "Footprint" ""
			(at 335.28 195.58 0)
			(effects
				(font
					(size 1.27 1.27)
				)
				(hide yes)
			)
		)
		(property "Datasheet" ""
			(at 335.28 195.58 0)
			(effects
				(font
					(size 1.27 1.27)
				)
				(hide yes)
			)
		)
		(property "Description" ""
			(at 335.28 195.58 0)
			(effects
				(font
					(size 1.27 1.27)
				)
				(hide yes)
			)
		)
		(pin "1"
		)
		(instances
			(project "gmsl-deserializer"
				(path ""
					(reference "#FLG0101")
					(unit 1)
				)
			)
		)
	)
	(symbol
		(lib_id "antmicroTestPoints:TP_0.75mm_SMD")
		(at 71.12 227.33 90)
		(unit 1)
		(exclude_from_sim no)
		(in_bom yes)
		(on_board yes)
		(dnp no)
		(fields_autoplaced yes)
		(property "Reference" "TP5"
			(at 73.66 224.1549 90)
			(effects
				(font
					(size 1.27 1.27)
					(thickness 0.15)
				)
				(justify right)
			)
		)
		(property "Value" "TP_0.75mm_SMD"
			(at 74.93 216.535 0)
			(effects
				(font
					(size 1.27 1.27)
					(thickness 0.15)
				)
				(justify left bottom)
				(hide yes)
			)
		)
		(property "Footprint" "antmicro-footprints:TP_SMD_0.75mm"
			(at 77.47 216.535 0)
			(effects
				(font
					(size 1.27 1.27)
					(thickness 0.15)
				)
				(justify left bottom)
				(hide yes)
			)
		)
		(property "Datasheet" ""
			(at 83.82 209.55 0)
			(effects
				(font
					(size 1.27 1.27)
					(thickness 0.15)
				)
				(justify left bottom)
				(hide yes)
			)
		)
		(property "Description" "SMT test point"
			(at 71.12 227.33 0)
			(effects
				(font
					(size 1.27 1.27)
				)
				(hide yes)
			)
		)
		(property "MPN" ""
			(at 82.55 216.535 0)
			(effects
				(font
					(size 1.27 1.27)
					(thickness 0.15)
				)
				(justify left bottom)
				(hide yes)
			)
		)
		(property "Manufacturer" ""
			(at 77.47 216.535 0)
			(effects
				(font
					(size 1.27 1.27)
					(thickness 0.15)
				)
				(justify left bottom)
				(hide yes)
			)
		)
		(property "Author" "Antmicro"
			(at 80.01 216.535 0)
			(effects
				(font
					(size 1.27 1.27)
					(thickness 0.15)
				)
				(justify left bottom)
				(hide yes)
			)
		)
		(property "License" "Apache-2.0"
			(at 82.55 216.535 0)
			(effects
				(font
					(size 1.27 1.27)
					(thickness 0.15)
				)
				(justify left bottom)
				(hide yes)
			)
		)
		(pin "1"
		)
		(instances
			(project "gmsl-deserializer"
				(path ""
					(reference "TP5")
					(unit 1)
				)
			)
		)
	)
	(symbol
		(lib_id "antmicropower:GND")
		(at 330.2 209.55 0)
		(unit 1)
		(exclude_from_sim no)
		(in_bom yes)
		(on_board yes)
		(dnp no)
		(property "Reference" "#PWR06"
			(at 339.09 212.09 0)
			(effects
				(font
					(size 1.27 1.27)
					(thickness 0.15)
				)
				(justify left bottom)
				(hide yes)
			)
		)
		(property "Value" "GND"
			(at 330.2 213.36 0)
			(effects
				(font
					(size 1.27 1.27)
					(thickness 0.15)
				)
			)
		)
		(property "Footprint" ""
			(at 339.09 217.17 0)
			(effects
				(font
					(size 1.27 1.27)
					(thickness 0.15)
				)
				(justify left bottom)
				(hide yes)
			)
		)
		(property "Datasheet" ""
			(at 339.09 222.25 0)
			(effects
				(font
					(size 1.27 1.27)
					(thickness 0.15)
				)
				(justify left bottom)
				(hide yes)
			)
		)
		(property "Description" ""
			(at 330.2 209.55 0)
			(effects
				(font
					(size 1.27 1.27)
				)
				(hide yes)
			)
		)
		(property "Author" "Antmicro"
			(at 339.09 217.17 0)
			(effects
				(font
					(size 1.27 1.27)
					(thickness 0.15)
				)
				(justify left bottom)
				(hide yes)
			)
		)
		(property "License" "Apache-2.0"
			(at 339.09 219.71 0)
			(effects
				(font
					(size 1.27 1.27)
					(thickness 0.15)
				)
				(justify left bottom)
				(hide yes)
			)
		)
		(pin "1"
		)
		(instances
			(project "gmsl-deserializer"
				(path ""
					(reference "#PWR06")
					(unit 1)
				)
			)
		)
	)
	(symbol
		(lib_id "antmicroResistors0402:R_2k2_0402")
		(at 190.5 130.81 270)
		(mirror x)
		(unit 1)
		(exclude_from_sim no)
		(in_bom no)
		(on_board yes)
		(dnp yes)
		(property "Reference" "R63"
			(at 189.23 127 90)
			(effects
				(font
					(size 1.27 1.27)
					(thickness 0.15)
				)
				(justify right)
			)
		)
		(property "Value" "R_2k2_0402"
			(at 177.8 110.49 0)
			(effects
				(font
					(size 1.27 1.27)
					(thickness 0.15)
				)
				(justify left bottom)
				(hide yes)
			)
		)
		(property "Footprint" "antmicro-footprints:R_0402_1005Metric"
			(at 175.26 110.49 0)
			(effects
				(font
					(size 1.27 1.27)
					(thickness 0.15)
				)
				(justify left bottom)
				(hide yes)
			)
		)
		(property "Datasheet" "https://www.bourns.com/docs/product-datasheets/cr.pdf"
			(at 172.72 110.49 0)
			(effects
				(font
					(size 1.27 1.27)
					(thickness 0.15)
				)
				(justify left bottom)
				(hide yes)
			)
		)
		(property "Description" "SMD Chip Resistor, 2.2 kohm, ± 1%, 62.5 mW, 0402 [1005 Metric], Thick Film, General Purpose"
			(at 190.5 130.81 0)
			(effects
				(font
					(size 1.27 1.27)
				)
				(hide yes)
			)
		)
		(property "MPN" "CR0402-FX-2201GLF"
			(at 170.18 110.49 0)
			(effects
				(font
					(size 1.27 1.27)
					(thickness 0.15)
				)
				(justify left bottom)
				(hide yes)
			)
		)
		(property "Manufacturer" "Bourns"
			(at 167.64 110.49 0)
			(effects
				(font
					(size 1.27 1.27)
					(thickness 0.15)
				)
				(justify left bottom)
				(hide yes)
			)
		)
		(property "License" "Apache-2.0"
			(at 165.1 110.49 0)
			(effects
				(font
					(size 1.27 1.27)
					(thickness 0.15)
				)
				(justify left bottom)
				(hide yes)
			)
		)
		(property "Author" "Antmicro"
			(at 162.56 110.49 0)
			(effects
				(font
					(size 1.27 1.27)
					(thickness 0.15)
				)
				(justify left bottom)
				(hide yes)
			)
		)
		(property "Val" "2k2"
			(at 189.23 129.54 90)
			(effects
				(font
					(size 1.27 1.27)
					(thickness 0.15)
				)
				(justify right)
			)
		)
		(property "Tolerance" "1%"
			(at 180.34 110.49 0)
			(effects
				(font
					(size 1.27 1.27)
				)
				(justify left bottom)
				(hide yes)
			)
		)
		(pin "1"
		)
		(pin "2"
		)
		(instances
			(project "gmsl-deserializer"
				(path ""
					(reference "R63")
					(unit 1)
				)
			)
		)
	)
	(symbol
		(lib_id "antmicropower:GND")
		(at 279.4 170.18 0)
		(unit 1)
		(exclude_from_sim no)
		(in_bom yes)
		(on_board yes)
		(dnp no)
		(property "Reference" "#PWR07"
			(at 288.29 172.72 0)
			(effects
				(font
					(size 1.27 1.27)
					(thickness 0.15)
				)
				(justify left bottom)
				(hide yes)
			)
		)
		(property "Value" "GND"
			(at 279.4 173.99 0)
			(effects
				(font
					(size 1.27 1.27)
					(thickness 0.15)
				)
			)
		)
		(property "Footprint" ""
			(at 288.29 177.8 0)
			(effects
				(font
					(size 1.27 1.27)
					(thickness 0.15)
				)
				(justify left bottom)
				(hide yes)
			)
		)
		(property "Datasheet" ""
			(at 288.29 182.88 0)
			(effects
				(font
					(size 1.27 1.27)
					(thickness 0.15)
				)
				(justify left bottom)
				(hide yes)
			)
		)
		(property "Description" ""
			(at 279.4 170.18 0)
			(effects
				(font
					(size 1.27 1.27)
				)
				(hide yes)
			)
		)
		(property "Author" "Antmicro"
			(at 288.29 177.8 0)
			(effects
				(font
					(size 1.27 1.27)
					(thickness 0.15)
				)
				(justify left bottom)
				(hide yes)
			)
		)
		(property "License" "Apache-2.0"
			(at 288.29 180.34 0)
			(effects
				(font
					(size 1.27 1.27)
					(thickness 0.15)
				)
				(justify left bottom)
				(hide yes)
			)
		)
		(pin "1"
		)
		(instances
			(project "gmsl-deserializer"
				(path ""
					(reference "#PWR07")
					(unit 1)
				)
			)
		)
	)
	(symbol
		(lib_id "antmicroResistors0402:R_100R_0402")
		(at 318.77 180.34 0)
		(unit 1)
		(exclude_from_sim no)
		(in_bom yes)
		(on_board yes)
		(dnp no)
		(property "Reference" "R12"
			(at 319.405 179.07 0)
			(effects
				(font
					(size 1.27 1.27)
					(thickness 0.15)
				)
				(justify right)
			)
		)
		(property "Value" "R_100R_0402"
			(at 339.09 193.04 0)
			(effects
				(font
					(size 1.27 1.27)
					(thickness 0.15)
				)
				(justify left bottom)
				(hide yes)
			)
		)
		(property "Footprint" "antmicro-footprints:R_0402_1005Metric"
			(at 339.09 195.58 0)
			(effects
				(font
					(size 1.27 1.27)
					(thickness 0.15)
				)
				(justify left bottom)
				(hide yes)
			)
		)
		(property "Datasheet" "https://www.bourns.com/docs/product-datasheets/cr.pdf"
			(at 339.09 198.12 0)
			(effects
				(font
					(size 1.27 1.27)
					(thickness 0.15)
				)
				(justify left bottom)
				(hide yes)
			)
		)
		(property "Description" "SMD Chip Resistor, 100 ohm, ± 1%, 62.5 mW, 0402 [1005 Metric], Thick Film, General Purpose"
			(at 318.77 180.34 0)
			(effects
				(font
					(size 1.27 1.27)
				)
				(hide yes)
			)
		)
		(property "MPN" "CR0402-FX-1000GLF"
			(at 339.09 200.66 0)
			(effects
				(font
					(size 1.27 1.27)
					(thickness 0.15)
				)
				(justify left bottom)
				(hide yes)
			)
		)
		(property "Manufacturer" "Bourns"
			(at 339.09 203.2 0)
			(effects
				(font
					(size 1.27 1.27)
					(thickness 0.15)
				)
				(justify left bottom)
				(hide yes)
			)
		)
		(property "License" "Apache-2.0"
			(at 339.09 205.74 0)
			(effects
				(font
					(size 1.27 1.27)
					(thickness 0.15)
				)
				(justify left bottom)
				(hide yes)
			)
		)
		(property "Author" "Antmicro"
			(at 339.09 208.28 0)
			(effects
				(font
					(size 1.27 1.27)
					(thickness 0.15)
				)
				(justify left bottom)
				(hide yes)
			)
		)
		(property "Val" "100R"
			(at 325.755 179.07 0)
			(effects
				(font
					(size 1.27 1.27)
					(thickness 0.15)
				)
			)
		)
		(property "Tolerance" "1%"
			(at 339.09 190.5 0)
			(effects
				(font
					(size 1.27 1.27)
				)
				(justify left bottom)
				(hide yes)
			)
		)
		(pin "1"
		)
		(pin "2"
		)
		(instances
			(project "gmsl-deserializer"
				(path ""
					(reference "R12")
					(unit 1)
				)
			)
		)
	)
	(symbol
		(lib_id "antmicroResistors0402:R_200R_0402")
		(at 259.08 223.52 90)
		(unit 1)
		(exclude_from_sim no)
		(in_bom yes)
		(on_board yes)
		(dnp no)
		(property "Reference" "R70"
			(at 256.54 219.71 90)
			(effects
				(font
					(size 1.27 1.27)
					(thickness 0.15)
				)
				(justify left)
			)
		)
		(property "Value" "R_200R_0402"
			(at 271.78 203.2 0)
			(effects
				(font
					(size 1.27 1.27)
					(thickness 0.15)
				)
				(justify left bottom)
				(hide yes)
			)
		)
		(property "Footprint" "antmicro-footprints:R_0402_1005Metric"
			(at 274.32 203.2 0)
			(effects
				(font
					(size 1.27 1.27)
					(thickness 0.15)
				)
				(justify left bottom)
				(hide yes)
			)
		)
		(property "Datasheet" "https://www.bourns.com/docs/product-datasheets/cr.pdf"
			(at 276.86 203.2 0)
			(effects
				(font
					(size 1.27 1.27)
					(thickness 0.15)
				)
				(justify left bottom)
				(hide yes)
			)
		)
		(property "Description" "SMD Chip Resistor, 200 ohm, ± 1%, 62.5 mW, 0402 [1005 Metric], Thick Film, General Purpose"
			(at 259.08 223.52 0)
			(effects
				(font
					(size 1.27 1.27)
				)
				(hide yes)
			)
		)
		(property "MPN" "CR0402-FX-2000GLF"
			(at 279.4 203.2 0)
			(effects
				(font
					(size 1.27 1.27)
					(thickness 0.15)
				)
				(justify left bottom)
				(hide yes)
			)
		)
		(property "Manufacturer" "Bourns"
			(at 281.94 203.2 0)
			(effects
				(font
					(size 1.27 1.27)
					(thickness 0.15)
				)
				(justify left bottom)
				(hide yes)
			)
		)
		(property "License" "Apache-2.0"
			(at 284.48 203.2 0)
			(effects
				(font
					(size 1.27 1.27)
					(thickness 0.15)
				)
				(justify left bottom)
				(hide yes)
			)
		)
		(property "Author" "Antmicro"
			(at 287.02 203.2 0)
			(effects
				(font
					(size 1.27 1.27)
					(thickness 0.15)
				)
				(justify left bottom)
				(hide yes)
			)
		)
		(property "Val" "200R"
			(at 256.54 222.25 90)
			(effects
				(font
					(size 1.27 1.27)
					(thickness 0.15)
				)
				(justify left)
			)
		)
		(property "Tolerance" "1%"
			(at 269.24 203.2 0)
			(effects
				(font
					(size 1.27 1.27)
				)
				(justify left bottom)
				(hide yes)
			)
		)
		(property "Public" ""
			(at 289.56 203.2 0)
			(effects
				(font
					(size 1.27 1.27)
				)
				(justify left bottom)
				(hide yes)
			)
		)
		(pin "2"
		)
		(pin "1"
		)
		(instances
			(project "gmsl-deserializer"
				(path ""
					(reference "R70")
					(unit 1)
				)
			)
		)
	)
	(symbol
		(lib_id "antmicropower:GND")
		(at 266.7 224.79 0)
		(unit 1)
		(exclude_from_sim no)
		(in_bom yes)
		(on_board yes)
		(dnp no)
		(property "Reference" "#PWR050"
			(at 275.59 227.33 0)
			(effects
				(font
					(size 1.27 1.27)
					(thickness 0.15)
				)
				(justify left bottom)
				(hide yes)
			)
		)
		(property "Value" "GND"
			(at 266.7 228.6 0)
			(effects
				(font
					(size 1.27 1.27)
					(thickness 0.15)
				)
			)
		)
		(property "Footprint" ""
			(at 275.59 232.41 0)
			(effects
				(font
					(size 1.27 1.27)
					(thickness 0.15)
				)
				(justify left bottom)
				(hide yes)
			)
		)
		(property "Datasheet" ""
			(at 275.59 237.49 0)
			(effects
				(font
					(size 1.27 1.27)
					(thickness 0.15)
				)
				(justify left bottom)
				(hide yes)
			)
		)
		(property "Description" ""
			(at 266.7 224.79 0)
			(effects
				(font
					(size 1.27 1.27)
				)
				(hide yes)
			)
		)
		(property "Author" "Antmicro"
			(at 275.59 232.41 0)
			(effects
				(font
					(size 1.27 1.27)
					(thickness 0.15)
				)
				(justify left bottom)
				(hide yes)
			)
		)
		(property "License" "Apache-2.0"
			(at 275.59 234.95 0)
			(effects
				(font
					(size 1.27 1.27)
					(thickness 0.15)
				)
				(justify left bottom)
				(hide yes)
			)
		)
		(pin "1"
		)
		(instances
			(project "gmsl-deserializer"
				(path ""
					(reference "#PWR050")
					(unit 1)
				)
			)
		)
	)
	(symbol
		(lib_id "antmicroTestPoints:TP_0.75mm_SMD")
		(at 53.34 200.66 0)
		(unit 1)
		(exclude_from_sim no)
		(in_bom yes)
		(on_board yes)
		(dnp no)
		(fields_autoplaced yes)
		(property "Reference" "TP2"
			(at 58.42 200.6599 0)
			(effects
				(font
					(size 1.27 1.27)
					(thickness 0.15)
				)
				(justify left)
			)
		)
		(property "Value" "TP_0.75mm_SMD"
			(at 64.135 204.47 0)
			(effects
				(font
					(size 1.27 1.27)
					(thickness 0.15)
				)
				(justify left bottom)
				(hide yes)
			)
		)
		(property "Footprint" "antmicro-footprints:TP_SMD_0.75mm"
			(at 64.135 207.01 0)
			(effects
				(font
					(size 1.27 1.27)
					(thickness 0.15)
				)
				(justify left bottom)
				(hide yes)
			)
		)
		(property "Datasheet" ""
			(at 71.12 213.36 0)
			(effects
				(font
					(size 1.27 1.27)
					(thickness 0.15)
				)
				(justify left bottom)
				(hide yes)
			)
		)
		(property "Description" "SMT test point"
			(at 53.34 200.66 0)
			(effects
				(font
					(size 1.27 1.27)
				)
				(hide yes)
			)
		)
		(property "MPN" ""
			(at 64.135 212.09 0)
			(effects
				(font
					(size 1.27 1.27)
					(thickness 0.15)
				)
				(justify left bottom)
				(hide yes)
			)
		)
		(property "Manufacturer" ""
			(at 64.135 207.01 0)
			(effects
				(font
					(size 1.27 1.27)
					(thickness 0.15)
				)
				(justify left bottom)
				(hide yes)
			)
		)
		(property "Author" "Antmicro"
			(at 64.135 209.55 0)
			(effects
				(font
					(size 1.27 1.27)
					(thickness 0.15)
				)
				(justify left bottom)
				(hide yes)
			)
		)
		(property "License" "Apache-2.0"
			(at 64.135 212.09 0)
			(effects
				(font
					(size 1.27 1.27)
					(thickness 0.15)
				)
				(justify left bottom)
				(hide yes)
			)
		)
		(pin "1"
		)
		(instances
			(project "gmsl-deserializer"
				(path ""
					(reference "TP2")
					(unit 1)
				)
			)
		)
	)
	(symbol
		(lib_id "antmicroTestPoints:TP_0.75mm_SMD")
		(at 49.53 68.58 90)
		(unit 1)
		(exclude_from_sim no)
		(in_bom yes)
		(on_board yes)
		(dnp no)
		(property "Reference" "TP22"
			(at 48.26 63.5 90)
			(effects
				(font
					(size 1.27 1.27)
					(thickness 0.15)
				)
				(justify right)
			)
		)
		(property "Value" "TP_0.75mm_SMD"
			(at 53.34 57.785 0)
			(effects
				(font
					(size 1.27 1.27)
					(thickness 0.15)
				)
				(justify left bottom)
				(hide yes)
			)
		)
		(property "Footprint" "antmicro-footprints:TP_SMD_0.75mm"
			(at 55.88 57.785 0)
			(effects
				(font
					(size 1.27 1.27)
					(thickness 0.15)
				)
				(justify left bottom)
				(hide yes)
			)
		)
		(property "Datasheet" ""
			(at 62.23 50.8 0)
			(effects
				(font
					(size 1.27 1.27)
					(thickness 0.15)
				)
				(justify left bottom)
				(hide yes)
			)
		)
		(property "Description" "SMT test point"
			(at 49.53 68.58 0)
			(effects
				(font
					(size 1.27 1.27)
				)
				(hide yes)
			)
		)
		(property "MPN" ""
			(at 60.96 57.785 0)
			(effects
				(font
					(size 1.27 1.27)
					(thickness 0.15)
				)
				(justify left bottom)
				(hide yes)
			)
		)
		(property "Manufacturer" ""
			(at 55.88 57.785 0)
			(effects
				(font
					(size 1.27 1.27)
					(thickness 0.15)
				)
				(justify left bottom)
				(hide yes)
			)
		)
		(property "Author" "Antmicro"
			(at 58.42 57.785 0)
			(effects
				(font
					(size 1.27 1.27)
					(thickness 0.15)
				)
				(justify left bottom)
				(hide yes)
			)
		)
		(property "License" "Apache-2.0"
			(at 60.96 57.785 0)
			(effects
				(font
					(size 1.27 1.27)
					(thickness 0.15)
				)
				(justify left bottom)
				(hide yes)
			)
		)
		(pin "1"
		)
		(instances
			(project "gmsl-deserializer"
				(path ""
					(reference "TP22")
					(unit 1)
				)
			)
		)
	)
	(symbol
		(lib_id "antmicroResistors0402:R_200R_0402")
		(at 289.56 162.56 90)
		(unit 1)
		(exclude_from_sim no)
		(in_bom no)
		(on_board yes)
		(dnp yes)
		(property "Reference" "R8"
			(at 287.655 158.75 0)
			(effects
				(font
					(size 1.27 1.27)
					(thickness 0.15)
				)
				(justify right)
			)
		)
		(property "Value" "R_200R_0402"
			(at 302.26 142.24 0)
			(effects
				(font
					(size 1.27 1.27)
					(thickness 0.15)
				)
				(justify left bottom)
				(hide yes)
			)
		)
		(property "Footprint" "antmicro-footprints:R_0402_1005Metric"
			(at 304.8 142.24 0)
			(effects
				(font
					(size 1.27 1.27)
					(thickness 0.15)
				)
				(justify left bottom)
				(hide yes)
			)
		)
		(property "Datasheet" "https://www.bourns.com/docs/product-datasheets/cr.pdf"
			(at 307.34 142.24 0)
			(effects
				(font
					(size 1.27 1.27)
					(thickness 0.15)
				)
				(justify left bottom)
				(hide yes)
			)
		)
		(property "Description" "SMD Chip Resistor, 200 ohm, ± 1%, 62.5 mW, 0402 [1005 Metric], Thick Film, General Purpose"
			(at 289.56 162.56 0)
			(effects
				(font
					(size 1.27 1.27)
				)
				(hide yes)
			)
		)
		(property "MPN" "CR0402-FX-2000GLF"
			(at 309.88 142.24 0)
			(effects
				(font
					(size 1.27 1.27)
					(thickness 0.15)
				)
				(justify left bottom)
				(hide yes)
			)
		)
		(property "Manufacturer" "Bourns"
			(at 312.42 142.24 0)
			(effects
				(font
					(size 1.27 1.27)
					(thickness 0.15)
				)
				(justify left bottom)
				(hide yes)
			)
		)
		(property "License" "Apache-2.0"
			(at 314.96 142.24 0)
			(effects
				(font
					(size 1.27 1.27)
					(thickness 0.15)
				)
				(justify left bottom)
				(hide yes)
			)
		)
		(property "Author" "Antmicro"
			(at 317.5 142.24 0)
			(effects
				(font
					(size 1.27 1.27)
					(thickness 0.15)
				)
				(justify left bottom)
				(hide yes)
			)
		)
		(property "Val" "200R"
			(at 291.465 157.48 0)
			(effects
				(font
					(size 1.27 1.27)
					(thickness 0.15)
				)
				(justify right)
			)
		)
		(property "Tolerance" "1%"
			(at 299.72 142.24 0)
			(effects
				(font
					(size 1.27 1.27)
				)
				(justify left bottom)
				(hide yes)
			)
		)
		(pin "1"
		)
		(pin "2"
		)
		(instances
			(project "gmsl-deserializer"
				(path ""
					(reference "R8")
					(unit 1)
				)
			)
		)
	)
	(symbol
		(lib_id "antmicropower:GND")
		(at 55.88 77.47 0)
		(unit 1)
		(exclude_from_sim no)
		(in_bom yes)
		(on_board yes)
		(dnp no)
		(property "Reference" "#PWR0102"
			(at 64.77 80.01 0)
			(effects
				(font
					(size 1.27 1.27)
					(thickness 0.15)
				)
				(justify left bottom)
				(hide yes)
			)
		)
		(property "Value" "GND"
			(at 55.88 81.28 0)
			(effects
				(font
					(size 1.27 1.27)
					(thickness 0.15)
				)
			)
		)
		(property "Footprint" ""
			(at 64.77 85.09 0)
			(effects
				(font
					(size 1.27 1.27)
					(thickness 0.15)
				)
				(justify left bottom)
				(hide yes)
			)
		)
		(property "Datasheet" ""
			(at 64.77 90.17 0)
			(effects
				(font
					(size 1.27 1.27)
					(thickness 0.15)
				)
				(justify left bottom)
				(hide yes)
			)
		)
		(property "Description" ""
			(at 55.88 77.47 0)
			(effects
				(font
					(size 1.27 1.27)
				)
				(hide yes)
			)
		)
		(property "Author" "Antmicro"
			(at 64.77 85.09 0)
			(effects
				(font
					(size 1.27 1.27)
					(thickness 0.15)
				)
				(justify left bottom)
				(hide yes)
			)
		)
		(property "License" "Apache-2.0"
			(at 64.77 87.63 0)
			(effects
				(font
					(size 1.27 1.27)
					(thickness 0.15)
				)
				(justify left bottom)
				(hide yes)
			)
		)
		(pin "1"
		)
		(instances
			(project "gmsl-deserializer"
				(path ""
					(reference "#PWR0102")
					(unit 1)
				)
			)
		)
	)
	(symbol
		(lib_id "antmicroResistors0402:R_100R_0402")
		(at 327.66 182.88 0)
		(unit 1)
		(exclude_from_sim no)
		(in_bom yes)
		(on_board yes)
		(dnp no)
		(property "Reference" "R14"
			(at 328.295 181.61 0)
			(effects
				(font
					(size 1.27 1.27)
					(thickness 0.15)
				)
				(justify right)
			)
		)
		(property "Value" "R_100R_0402"
			(at 347.98 195.58 0)
			(effects
				(font
					(size 1.27 1.27)
					(thickness 0.15)
				)
				(justify left bottom)
				(hide yes)
			)
		)
		(property "Footprint" "antmicro-footprints:R_0402_1005Metric"
			(at 347.98 198.12 0)
			(effects
				(font
					(size 1.27 1.27)
					(thickness 0.15)
				)
				(justify left bottom)
				(hide yes)
			)
		)
		(property "Datasheet" "https://www.bourns.com/docs/product-datasheets/cr.pdf"
			(at 347.98 200.66 0)
			(effects
				(font
					(size 1.27 1.27)
					(thickness 0.15)
				)
				(justify left bottom)
				(hide yes)
			)
		)
		(property "Description" "SMD Chip Resistor, 100 ohm, ± 1%, 62.5 mW, 0402 [1005 Metric], Thick Film, General Purpose"
			(at 327.66 182.88 0)
			(effects
				(font
					(size 1.27 1.27)
				)
				(hide yes)
			)
		)
		(property "MPN" "CR0402-FX-1000GLF"
			(at 347.98 203.2 0)
			(effects
				(font
					(size 1.27 1.27)
					(thickness 0.15)
				)
				(justify left bottom)
				(hide yes)
			)
		)
		(property "Manufacturer" "Bourns"
			(at 347.98 205.74 0)
			(effects
				(font
					(size 1.27 1.27)
					(thickness 0.15)
				)
				(justify left bottom)
				(hide yes)
			)
		)
		(property "License" "Apache-2.0"
			(at 347.98 208.28 0)
			(effects
				(font
					(size 1.27 1.27)
					(thickness 0.15)
				)
				(justify left bottom)
				(hide yes)
			)
		)
		(property "Author" "Antmicro"
			(at 347.98 210.82 0)
			(effects
				(font
					(size 1.27 1.27)
					(thickness 0.15)
				)
				(justify left bottom)
				(hide yes)
			)
		)
		(property "Val" "100R"
			(at 334.645 181.61 0)
			(effects
				(font
					(size 1.27 1.27)
					(thickness 0.15)
				)
			)
		)
		(property "Tolerance" "1%"
			(at 347.98 193.04 0)
			(effects
				(font
					(size 1.27 1.27)
				)
				(justify left bottom)
				(hide yes)
			)
		)
		(pin "1"
		)
		(pin "2"
		)
		(instances
			(project "gmsl-deserializer"
				(path ""
					(reference "R14")
					(unit 1)
				)
			)
		)
	)
	(symbol
		(lib_id "antmicroResistors0402:R_0R_0402")
		(at 148.59 72.39 0)
		(mirror y)
		(unit 1)
		(exclude_from_sim no)
		(in_bom yes)
		(on_board yes)
		(dnp no)
		(property "Reference" "R2"
			(at 142.24 71.12 0)
			(effects
				(font
					(size 1.27 1.27)
					(thickness 0.15)
				)
			)
		)
		(property "Value" "R_0R_0402"
			(at 128.27 85.09 0)
			(effects
				(font
					(size 1.27 1.27)
					(thickness 0.15)
				)
				(justify left bottom)
				(hide yes)
			)
		)
		(property "Footprint" "antmicro-footprints:R_0402_1005Metric"
			(at 128.27 87.63 0)
			(effects
				(font
					(size 1.27 1.27)
					(thickness 0.15)
				)
				(justify left bottom)
				(hide yes)
			)
		)
		(property "Datasheet" "https://industrial.panasonic.com/cdbs/www-data/pdf/RDA0000/AOA0000C301.pdf"
			(at 128.27 90.17 0)
			(effects
				(font
					(size 1.27 1.27)
					(thickness 0.15)
				)
				(justify left bottom)
				(hide yes)
			)
		)
		(property "Description" "SMD Chip Resistor, Jumper, 0 ohm, 100 mW, 0402 [1005 Metric], Thick Film, General Purpose"
			(at 148.59 72.39 0)
			(effects
				(font
					(size 1.27 1.27)
				)
				(hide yes)
			)
		)
		(property "MPN" "ERJ2GE0R00X"
			(at 128.27 92.71 0)
			(effects
				(font
					(size 1.27 1.27)
					(thickness 0.15)
				)
				(justify left bottom)
				(hide yes)
			)
		)
		(property "Manufacturer" "Panasonic"
			(at 128.27 95.25 0)
			(effects
				(font
					(size 1.27 1.27)
					(thickness 0.15)
				)
				(justify left bottom)
				(hide yes)
			)
		)
		(property "License" "Apache-2.0"
			(at 128.27 97.79 0)
			(effects
				(font
					(size 1.27 1.27)
					(thickness 0.15)
				)
				(justify left bottom)
				(hide yes)
			)
		)
		(property "Author" "Antmicro"
			(at 128.27 100.33 0)
			(effects
				(font
					(size 1.27 1.27)
					(thickness 0.15)
				)
				(justify left bottom)
				(hide yes)
			)
		)
		(property "Val" "0R"
			(at 149.225 71.12 0)
			(effects
				(font
					(size 1.27 1.27)
					(thickness 0.15)
				)
			)
		)
		(property "Tolerance" "~"
			(at 128.27 82.55 0)
			(effects
				(font
					(size 1.27 1.27)
				)
				(justify left bottom)
				(hide yes)
			)
		)
		(property "Current" "1A"
			(at 128.27 102.87 0)
			(effects
				(font
					(size 1.27 1.27)
					(thickness 0.15)
				)
				(justify left bottom)
				(hide yes)
			)
		)
		(pin "1"
		)
		(pin "2"
		)
		(instances
			(project "gmsl-deserializer"
				(path ""
					(reference "R2")
					(unit 1)
				)
			)
		)
	)
	(symbol
		(lib_id "antmicropower:GND")
		(at 120.65 80.01 0)
		(unit 1)
		(exclude_from_sim no)
		(in_bom yes)
		(on_board yes)
		(dnp no)
		(property "Reference" "#PWR09"
			(at 129.54 82.55 0)
			(effects
				(font
					(size 1.27 1.27)
					(thickness 0.15)
				)
				(justify left bottom)
				(hide yes)
			)
		)
		(property "Value" "GND"
			(at 120.65 83.82 0)
			(effects
				(font
					(size 1.27 1.27)
					(thickness 0.15)
				)
			)
		)
		(property "Footprint" ""
			(at 129.54 87.63 0)
			(effects
				(font
					(size 1.27 1.27)
					(thickness 0.15)
				)
				(justify left bottom)
				(hide yes)
			)
		)
		(property "Datasheet" ""
			(at 129.54 92.71 0)
			(effects
				(font
					(size 1.27 1.27)
					(thickness 0.15)
				)
				(justify left bottom)
				(hide yes)
			)
		)
		(property "Description" ""
			(at 120.65 80.01 0)
			(effects
				(font
					(size 1.27 1.27)
				)
				(hide yes)
			)
		)
		(property "Author" "Antmicro"
			(at 129.54 87.63 0)
			(effects
				(font
					(size 1.27 1.27)
					(thickness 0.15)
				)
				(justify left bottom)
				(hide yes)
			)
		)
		(property "License" "Apache-2.0"
			(at 129.54 90.17 0)
			(effects
				(font
					(size 1.27 1.27)
					(thickness 0.15)
				)
				(justify left bottom)
				(hide yes)
			)
		)
		(pin "1"
		)
		(instances
			(project "gmsl-deserializer"
				(path ""
					(reference "#PWR09")
					(unit 1)
				)
			)
		)
	)
	(symbol
		(lib_id "antmicroLogicBuffersDriversReceiversTransceivers:SN74LV1T125DBVR")
		(at 123.19 68.58 0)
		(unit 1)
		(exclude_from_sim no)
		(in_bom yes)
		(on_board yes)
		(dnp no)
		(fields_autoplaced yes)
		(property "Reference" "U1"
			(at 130.175 60.96 0)
			(effects
				(font
					(size 1.27 1.27)
					(thickness 0.15)
				)
			)
		)
		(property "Value" "SN74LV1T125DBVR"
			(at 130.175 63.5 0)
			(effects
				(font
					(size 1.27 1.27)
					(thickness 0.15)
				)
			)
		)
		(property "Footprint" "antmicro-footprints:SOT-23-5"
			(at 151.13 78.74 0)
			(effects
				(font
					(size 1.27 1.27)
					(thickness 0.15)
				)
				(justify left bottom)
				(hide yes)
			)
		)
		(property "Datasheet" "https://www.ti.com/lit/ds/symlink/sn74lv1t125.pdf?HQS=dis-mous-null-mousermode-dsf-pf-null-wwe&ts=1627648952184&ref_url=https%253A%252F%252Fmouser.com%252F"
			(at 151.13 81.28 0)
			(effects
				(font
					(size 1.27 1.27)
					(thickness 0.15)
				)
				(justify left bottom)
				(hide yes)
			)
		)
		(property "Description" "Buffer, 74LV1T125, 1.6 V to 5.5 V, SOT-23-5"
			(at 123.19 68.58 0)
			(effects
				(font
					(size 1.27 1.27)
				)
				(hide yes)
			)
		)
		(property "MPN" "SN74LV1T125DBVR"
			(at 151.13 83.82 0)
			(effects
				(font
					(size 1.27 1.27)
					(thickness 0.15)
				)
				(justify left bottom)
				(hide yes)
			)
		)
		(property "Manufacturer" "Texas Instruments"
			(at 151.13 86.36 0)
			(effects
				(font
					(size 1.27 1.27)
					(thickness 0.15)
				)
				(justify left bottom)
				(hide yes)
			)
		)
		(property "Author" "Antmicro"
			(at 151.13 88.9 0)
			(effects
				(font
					(size 1.27 1.27)
					(thickness 0.15)
				)
				(justify left bottom)
				(hide yes)
			)
		)
		(property "License" "Apache-2.0"
			(at 151.13 91.44 0)
			(effects
				(font
					(size 1.27 1.27)
					(thickness 0.15)
				)
				(justify left bottom)
				(hide yes)
			)
		)
		(pin "1"
		)
		(pin "2"
		)
		(pin "3"
		)
		(pin "4"
		)
		(pin "5"
		)
		(instances
			(project "gmsl-deserializer"
				(path ""
					(reference "U1")
					(unit 1)
				)
			)
		)
	)
	(symbol
		(lib_id "antmicropower:PWR_FLAG")
		(at 342.9 200.66 0)
		(unit 1)
		(exclude_from_sim no)
		(in_bom yes)
		(on_board yes)
		(dnp no)
		(property "Reference" "#FLG0102"
			(at 342.9 198.755 0)
			(effects
				(font
					(size 1.27 1.27)
				)
				(hide yes)
			)
		)
		(property "Value" "PWR_FLAG"
			(at 342.9 196.85 0)
			(effects
				(font
					(size 1.27 1.27)
				)
			)
		)
		(property "Footprint" ""
			(at 342.9 200.66 0)
			(effects
				(font
					(size 1.27 1.27)
				)
				(hide yes)
			)
		)
		(property "Datasheet" ""
			(at 342.9 200.66 0)
			(effects
				(font
					(size 1.27 1.27)
				)
				(hide yes)
			)
		)
		(property "Description" ""
			(at 342.9 200.66 0)
			(effects
				(font
					(size 1.27 1.27)
				)
				(hide yes)
			)
		)
		(pin "1"
		)
		(instances
			(project "gmsl-deserializer"
				(path ""
					(reference "#FLG0102")
					(unit 1)
				)
			)
		)
	)
	(symbol
		(lib_id "antmicroLogicBuffersDriversReceiversTransceivers:SN74LV1T125DBVR")
		(at 177.8 68.58 0)
		(unit 1)
		(exclude_from_sim no)
		(in_bom yes)
		(on_board yes)
		(dnp no)
		(fields_autoplaced yes)
		(property "Reference" "U2"
			(at 184.785 60.96 0)
			(effects
				(font
					(size 1.27 1.27)
					(thickness 0.15)
				)
			)
		)
		(property "Value" "SN74LV1T125DBVR"
			(at 184.785 63.5 0)
			(effects
				(font
					(size 1.27 1.27)
					(thickness 0.15)
				)
			)
		)
		(property "Footprint" "antmicro-footprints:SOT-23-5"
			(at 205.74 78.74 0)
			(effects
				(font
					(size 1.27 1.27)
					(thickness 0.15)
				)
				(justify left bottom)
				(hide yes)
			)
		)
		(property "Datasheet" "https://www.ti.com/lit/ds/symlink/sn74lv1t125.pdf?HQS=dis-mous-null-mousermode-dsf-pf-null-wwe&ts=1627648952184&ref_url=https%253A%252F%252Fmouser.com%252F"
			(at 205.74 81.28 0)
			(effects
				(font
					(size 1.27 1.27)
					(thickness 0.15)
				)
				(justify left bottom)
				(hide yes)
			)
		)
		(property "Description" "Buffer, 74LV1T125, 1.6 V to 5.5 V, SOT-23-5"
			(at 177.8 68.58 0)
			(effects
				(font
					(size 1.27 1.27)
				)
				(hide yes)
			)
		)
		(property "MPN" "SN74LV1T125DBVR"
			(at 205.74 83.82 0)
			(effects
				(font
					(size 1.27 1.27)
					(thickness 0.15)
				)
				(justify left bottom)
				(hide yes)
			)
		)
		(property "Manufacturer" "Texas Instruments"
			(at 205.74 86.36 0)
			(effects
				(font
					(size 1.27 1.27)
					(thickness 0.15)
				)
				(justify left bottom)
				(hide yes)
			)
		)
		(property "Author" "Antmicro"
			(at 205.74 88.9 0)
			(effects
				(font
					(size 1.27 1.27)
					(thickness 0.15)
				)
				(justify left bottom)
				(hide yes)
			)
		)
		(property "License" "Apache-2.0"
			(at 205.74 91.44 0)
			(effects
				(font
					(size 1.27 1.27)
					(thickness 0.15)
				)
				(justify left bottom)
				(hide yes)
			)
		)
		(pin "1"
		)
		(pin "2"
		)
		(pin "3"
		)
		(pin "4"
		)
		(pin "5"
		)
		(instances
			(project "gmsl-deserializer"
				(path ""
					(reference "U2")
					(unit 1)
				)
			)
		)
	)
	(symbol
		(lib_id "antmicroTestPoints:TP_0.75mm_SMD")
		(at 317.5 195.58 90)
		(unit 1)
		(exclude_from_sim no)
		(in_bom yes)
		(on_board yes)
		(dnp no)
		(property "Reference" "TP8"
			(at 318.77 192.405 90)
			(effects
				(font
					(size 1.27 1.27)
					(thickness 0.15)
				)
				(justify right)
			)
		)
		(property "Value" "TP_0.75mm_SMD"
			(at 321.31 184.785 0)
			(effects
				(font
					(size 1.27 1.27)
					(thickness 0.15)
				)
				(justify left bottom)
				(hide yes)
			)
		)
		(property "Footprint" "antmicro-footprints:TP_SMD_0.75mm"
			(at 323.85 184.785 0)
			(effects
				(font
					(size 1.27 1.27)
					(thickness 0.15)
				)
				(justify left bottom)
				(hide yes)
			)
		)
		(property "Datasheet" ""
			(at 330.2 177.8 0)
			(effects
				(font
					(size 1.27 1.27)
					(thickness 0.15)
				)
				(justify left bottom)
				(hide yes)
			)
		)
		(property "Description" "SMT test point"
			(at 317.5 195.58 0)
			(effects
				(font
					(size 1.27 1.27)
				)
				(hide yes)
			)
		)
		(property "MPN" ""
			(at 328.93 184.785 0)
			(effects
				(font
					(size 1.27 1.27)
					(thickness 0.15)
				)
				(justify left bottom)
				(hide yes)
			)
		)
		(property "Manufacturer" ""
			(at 323.85 184.785 0)
			(effects
				(font
					(size 1.27 1.27)
					(thickness 0.15)
				)
				(justify left bottom)
				(hide yes)
			)
		)
		(property "Author" "Antmicro"
			(at 326.39 184.785 0)
			(effects
				(font
					(size 1.27 1.27)
					(thickness 0.15)
				)
				(justify left bottom)
				(hide yes)
			)
		)
		(property "License" "Apache-2.0"
			(at 328.93 184.785 0)
			(effects
				(font
					(size 1.27 1.27)
					(thickness 0.15)
				)
				(justify left bottom)
				(hide yes)
			)
		)
		(pin "1"
		)
		(instances
			(project "gmsl-deserializer"
				(path ""
					(reference "TP8")
					(unit 1)
				)
			)
		)
	)
	(symbol
		(lib_id "antmicroResistors0402:R_0R_0402")
		(at 148.59 76.2 0)
		(mirror y)
		(unit 1)
		(exclude_from_sim no)
		(in_bom yes)
		(on_board yes)
		(dnp no)
		(property "Reference" "R3"
			(at 142.24 74.93 0)
			(effects
				(font
					(size 1.27 1.27)
					(thickness 0.15)
				)
			)
		)
		(property "Value" "R_0R_0402"
			(at 128.27 88.9 0)
			(effects
				(font
					(size 1.27 1.27)
					(thickness 0.15)
				)
				(justify left bottom)
				(hide yes)
			)
		)
		(property "Footprint" "antmicro-footprints:R_0402_1005Metric"
			(at 128.27 91.44 0)
			(effects
				(font
					(size 1.27 1.27)
					(thickness 0.15)
				)
				(justify left bottom)
				(hide yes)
			)
		)
		(property "Datasheet" "https://industrial.panasonic.com/cdbs/www-data/pdf/RDA0000/AOA0000C301.pdf"
			(at 128.27 93.98 0)
			(effects
				(font
					(size 1.27 1.27)
					(thickness 0.15)
				)
				(justify left bottom)
				(hide yes)
			)
		)
		(property "Description" "SMD Chip Resistor, Jumper, 0 ohm, 100 mW, 0402 [1005 Metric], Thick Film, General Purpose"
			(at 148.59 76.2 0)
			(effects
				(font
					(size 1.27 1.27)
				)
				(hide yes)
			)
		)
		(property "MPN" "ERJ2GE0R00X"
			(at 128.27 96.52 0)
			(effects
				(font
					(size 1.27 1.27)
					(thickness 0.15)
				)
				(justify left bottom)
				(hide yes)
			)
		)
		(property "Manufacturer" "Panasonic"
			(at 128.27 99.06 0)
			(effects
				(font
					(size 1.27 1.27)
					(thickness 0.15)
				)
				(justify left bottom)
				(hide yes)
			)
		)
		(property "License" "Apache-2.0"
			(at 128.27 101.6 0)
			(effects
				(font
					(size 1.27 1.27)
					(thickness 0.15)
				)
				(justify left bottom)
				(hide yes)
			)
		)
		(property "Author" "Antmicro"
			(at 128.27 104.14 0)
			(effects
				(font
					(size 1.27 1.27)
					(thickness 0.15)
				)
				(justify left bottom)
				(hide yes)
			)
		)
		(property "Val" "0R"
			(at 149.225 74.93 0)
			(effects
				(font
					(size 1.27 1.27)
					(thickness 0.15)
				)
			)
		)
		(property "Tolerance" "~"
			(at 128.27 86.36 0)
			(effects
				(font
					(size 1.27 1.27)
				)
				(justify left bottom)
				(hide yes)
			)
		)
		(property "Current" "1A"
			(at 128.27 106.68 0)
			(effects
				(font
					(size 1.27 1.27)
					(thickness 0.15)
				)
				(justify left bottom)
				(hide yes)
			)
		)
		(pin "1"
		)
		(pin "2"
		)
		(instances
			(project "gmsl-deserializer"
				(path ""
					(reference "R3")
					(unit 1)
				)
			)
		)
	)
	(symbol
		(lib_id "antmicroResistors0402:R_470R_0402")
		(at 66.04 110.49 90)
		(unit 1)
		(exclude_from_sim no)
		(in_bom yes)
		(on_board yes)
		(dnp no)
		(fields_autoplaced yes)
		(property "Reference" "R7"
			(at 68.58 106.6799 90)
			(effects
				(font
					(size 1.27 1.27)
					(thickness 0.15)
				)
				(justify right)
			)
		)
		(property "Value" "R_470R_0402"
			(at 78.74 90.17 0)
			(effects
				(font
					(size 1.27 1.27)
					(thickness 0.15)
				)
				(justify left bottom)
				(hide yes)
			)
		)
		(property "Footprint" "antmicro-footprints:R_0402_1005Metric"
			(at 81.28 90.17 0)
			(effects
				(font
					(size 1.27 1.27)
					(thickness 0.15)
				)
				(justify left bottom)
				(hide yes)
			)
		)
		(property "Datasheet" "https://www.bourns.com/docs/product-datasheets/cr.pdf"
			(at 83.82 90.17 0)
			(effects
				(font
					(size 1.27 1.27)
					(thickness 0.15)
				)
				(justify left bottom)
				(hide yes)
			)
		)
		(property "Description" "SMD Chip Resistor, 470 ohm, ± 1%, 62.5 mW, 0402 [1005 Metric], Thick Film, General Purpose"
			(at 66.04 110.49 0)
			(effects
				(font
					(size 1.27 1.27)
				)
				(hide yes)
			)
		)
		(property "MPN" "CR0402-FX-4700GLF"
			(at 86.36 90.17 0)
			(effects
				(font
					(size 1.27 1.27)
					(thickness 0.15)
				)
				(justify left bottom)
				(hide yes)
			)
		)
		(property "Manufacturer" "Bourns"
			(at 88.9 90.17 0)
			(effects
				(font
					(size 1.27 1.27)
					(thickness 0.15)
				)
				(justify left bottom)
				(hide yes)
			)
		)
		(property "License" "Apache-2.0"
			(at 91.44 90.17 0)
			(effects
				(font
					(size 1.27 1.27)
					(thickness 0.15)
				)
				(justify left bottom)
				(hide yes)
			)
		)
		(property "Author" "Antmicro"
			(at 93.98 90.17 0)
			(effects
				(font
					(size 1.27 1.27)
					(thickness 0.15)
				)
				(justify left bottom)
				(hide yes)
			)
		)
		(property "Val" "470R"
			(at 68.58 109.2199 90)
			(effects
				(font
					(size 1.27 1.27)
					(thickness 0.15)
				)
				(justify right)
			)
		)
		(property "Tolerance" "1%"
			(at 76.2 90.17 0)
			(effects
				(font
					(size 1.27 1.27)
				)
				(justify left bottom)
				(hide yes)
			)
		)
		(pin "1"
		)
		(pin "2"
		)
		(instances
			(project "gmsl-deserializer"
				(path ""
					(reference "R7")
					(unit 1)
				)
			)
		)
	)
	(symbol
		(lib_id "antmicroResistors0402:R_2k2_0402")
		(at 184.15 130.81 270)
		(mirror x)
		(unit 1)
		(exclude_from_sim no)
		(in_bom no)
		(on_board yes)
		(dnp yes)
		(property "Reference" "R61"
			(at 182.88 127 90)
			(effects
				(font
					(size 1.27 1.27)
					(thickness 0.15)
				)
				(justify right)
			)
		)
		(property "Value" "R_2k2_0402"
			(at 171.45 110.49 0)
			(effects
				(font
					(size 1.27 1.27)
					(thickness 0.15)
				)
				(justify left bottom)
				(hide yes)
			)
		)
		(property "Footprint" "antmicro-footprints:R_0402_1005Metric"
			(at 168.91 110.49 0)
			(effects
				(font
					(size 1.27 1.27)
					(thickness 0.15)
				)
				(justify left bottom)
				(hide yes)
			)
		)
		(property "Datasheet" "https://www.bourns.com/docs/product-datasheets/cr.pdf"
			(at 166.37 110.49 0)
			(effects
				(font
					(size 1.27 1.27)
					(thickness 0.15)
				)
				(justify left bottom)
				(hide yes)
			)
		)
		(property "Description" "SMD Chip Resistor, 2.2 kohm, ± 1%, 62.5 mW, 0402 [1005 Metric], Thick Film, General Purpose"
			(at 184.15 130.81 0)
			(effects
				(font
					(size 1.27 1.27)
				)
				(hide yes)
			)
		)
		(property "MPN" "CR0402-FX-2201GLF"
			(at 163.83 110.49 0)
			(effects
				(font
					(size 1.27 1.27)
					(thickness 0.15)
				)
				(justify left bottom)
				(hide yes)
			)
		)
		(property "Manufacturer" "Bourns"
			(at 161.29 110.49 0)
			(effects
				(font
					(size 1.27 1.27)
					(thickness 0.15)
				)
				(justify left bottom)
				(hide yes)
			)
		)
		(property "License" "Apache-2.0"
			(at 158.75 110.49 0)
			(effects
				(font
					(size 1.27 1.27)
					(thickness 0.15)
				)
				(justify left bottom)
				(hide yes)
			)
		)
		(property "Author" "Antmicro"
			(at 156.21 110.49 0)
			(effects
				(font
					(size 1.27 1.27)
					(thickness 0.15)
				)
				(justify left bottom)
				(hide yes)
			)
		)
		(property "Val" "2k2"
			(at 182.88 129.54 90)
			(effects
				(font
					(size 1.27 1.27)
					(thickness 0.15)
				)
				(justify right)
			)
		)
		(property "Tolerance" "1%"
			(at 173.99 110.49 0)
			(effects
				(font
					(size 1.27 1.27)
				)
				(justify left bottom)
				(hide yes)
			)
		)
		(pin "1"
		)
		(pin "2"
		)
		(instances
			(project "gmsl-deserializer"
				(path ""
					(reference "R61")
					(unit 1)
				)
			)
		)
	)
	(symbol
		(lib_id "antmicropower:GND")
		(at 337.82 209.55 0)
		(unit 1)
		(exclude_from_sim no)
		(in_bom yes)
		(on_board yes)
		(dnp no)
		(property "Reference" "#PWR018"
			(at 346.71 212.09 0)
			(effects
				(font
					(size 1.27 1.27)
					(thickness 0.15)
				)
				(justify left bottom)
				(hide yes)
			)
		)
		(property "Value" "GND"
			(at 337.82 213.36 0)
			(effects
				(font
					(size 1.27 1.27)
					(thickness 0.15)
				)
			)
		)
		(property "Footprint" ""
			(at 346.71 217.17 0)
			(effects
				(font
					(size 1.27 1.27)
					(thickness 0.15)
				)
				(justify left bottom)
				(hide yes)
			)
		)
		(property "Datasheet" ""
			(at 346.71 222.25 0)
			(effects
				(font
					(size 1.27 1.27)
					(thickness 0.15)
				)
				(justify left bottom)
				(hide yes)
			)
		)
		(property "Description" ""
			(at 337.82 209.55 0)
			(effects
				(font
					(size 1.27 1.27)
				)
				(hide yes)
			)
		)
		(property "Author" "Antmicro"
			(at 346.71 217.17 0)
			(effects
				(font
					(size 1.27 1.27)
					(thickness 0.15)
				)
				(justify left bottom)
				(hide yes)
			)
		)
		(property "License" "Apache-2.0"
			(at 346.71 219.71 0)
			(effects
				(font
					(size 1.27 1.27)
					(thickness 0.15)
				)
				(justify left bottom)
				(hide yes)
			)
		)
		(pin "1"
		)
		(instances
			(project "gmsl-deserializer"
				(path ""
					(reference "#PWR018")
					(unit 1)
				)
			)
		)
	)
	(symbol
		(lib_id "antmicroTransistorsFETsMOSFETsSingle:DMG1012T-7")
		(at 35.56 246.38 0)
		(unit 1)
		(exclude_from_sim no)
		(in_bom yes)
		(on_board yes)
		(dnp no)
		(fields_autoplaced yes)
		(property "Reference" "Q6"
			(at 45.72 242.57 0)
			(effects
				(font
					(size 1.27 1.27)
					(thickness 0.15)
				)
				(justify left)
			)
		)
		(property "Value" "DMG1012T-7"
			(at 45.72 250.19 0)
			(effects
				(font
					(size 1.27 1.27)
					(thickness 0.15)
				)
				(justify left bottom)
				(hide yes)
			)
		)
		(property "Footprint" "antmicro-footprints:SOT-523"
			(at 45.72 252.73 0)
			(effects
				(font
					(size 1.27 1.27)
					(thickness 0.15)
				)
				(justify left bottom)
				(hide yes)
			)
		)
		(property "Datasheet" "https://www.diodes.com/assets/Datasheets/ds31783.pdf"
			(at 45.72 255.27 0)
			(effects
				(font
					(size 1.27 1.27)
					(thickness 0.15)
				)
				(justify left bottom)
				(hide yes)
			)
		)
		(property "Description" "Power MOSFET, N Channel, 20 V, 630 mA, 0.3 ohm, SOT-523, Surface Mount"
			(at 35.56 246.38 0)
			(effects
				(font
					(size 1.27 1.27)
				)
				(hide yes)
			)
		)
		(property "MPN" "DMG1012T-7"
			(at 45.72 245.11 0)
			(effects
				(font
					(size 1.27 1.27)
					(thickness 0.15)
				)
				(justify left)
			)
		)
		(property "Manufacturer" "Diodes Incorporated"
			(at 45.72 247.65 0)
			(effects
				(font
					(size 1.27 1.27)
					(thickness 0.15)
				)
				(justify left bottom)
				(hide yes)
			)
		)
		(property "Author" "Antmicro"
			(at 45.72 257.81 0)
			(effects
				(font
					(size 1.27 1.27)
					(thickness 0.15)
				)
				(justify left bottom)
				(hide yes)
			)
		)
		(property "License" "Apache-2.0"
			(at 45.72 260.35 0)
			(effects
				(font
					(size 1.27 1.27)
					(thickness 0.15)
				)
				(justify left bottom)
				(hide yes)
			)
		)
		(property "Public" ""
			(at 55.88 254 0)
			(effects
				(font
					(size 1.27 1.27)
				)
				(justify left bottom)
				(hide yes)
			)
		)
		(pin "2"
		)
		(pin "3"
		)
		(pin "1"
		)
		(instances
			(project "gmsl-deserializer"
				(path ""
					(reference "Q6")
					(unit 1)
				)
			)
		)
	)
	(symbol
		(lib_id "antmicropower:GND")
		(at 45.72 77.47 0)
		(unit 1)
		(exclude_from_sim no)
		(in_bom yes)
		(on_board yes)
		(dnp no)
		(property "Reference" "#PWR0104"
			(at 54.61 80.01 0)
			(effects
				(font
					(size 1.27 1.27)
					(thickness 0.15)
				)
				(justify left bottom)
				(hide yes)
			)
		)
		(property "Value" "GND"
			(at 45.72 81.28 0)
			(effects
				(font
					(size 1.27 1.27)
					(thickness 0.15)
				)
			)
		)
		(property "Footprint" ""
			(at 54.61 85.09 0)
			(effects
				(font
					(size 1.27 1.27)
					(thickness 0.15)
				)
				(justify left bottom)
				(hide yes)
			)
		)
		(property "Datasheet" ""
			(at 54.61 90.17 0)
			(effects
				(font
					(size 1.27 1.27)
					(thickness 0.15)
				)
				(justify left bottom)
				(hide yes)
			)
		)
		(property "Description" ""
			(at 45.72 77.47 0)
			(effects
				(font
					(size 1.27 1.27)
				)
				(hide yes)
			)
		)
		(property "Author" "Antmicro"
			(at 54.61 85.09 0)
			(effects
				(font
					(size 1.27 1.27)
					(thickness 0.15)
				)
				(justify left bottom)
				(hide yes)
			)
		)
		(property "License" "Apache-2.0"
			(at 54.61 87.63 0)
			(effects
				(font
					(size 1.27 1.27)
					(thickness 0.15)
				)
				(justify left bottom)
				(hide yes)
			)
		)
		(pin "1"
		)
		(instances
			(project "gmsl-deserializer"
				(path ""
					(reference "#PWR0104")
					(unit 1)
				)
			)
		)
	)
	(symbol
		(lib_id "antmicropower:GND")
		(at 138.43 77.47 0)
		(unit 1)
		(exclude_from_sim no)
		(in_bom yes)
		(on_board yes)
		(dnp no)
		(property "Reference" "#PWR010"
			(at 147.32 80.01 0)
			(effects
				(font
					(size 1.27 1.27)
					(thickness 0.15)
				)
				(justify left bottom)
				(hide yes)
			)
		)
		(property "Value" "GND"
			(at 138.43 81.28 0)
			(effects
				(font
					(size 1.27 1.27)
					(thickness 0.15)
				)
			)
		)
		(property "Footprint" ""
			(at 147.32 85.09 0)
			(effects
				(font
					(size 1.27 1.27)
					(thickness 0.15)
				)
				(justify left bottom)
				(hide yes)
			)
		)
		(property "Datasheet" ""
			(at 147.32 90.17 0)
			(effects
				(font
					(size 1.27 1.27)
					(thickness 0.15)
				)
				(justify left bottom)
				(hide yes)
			)
		)
		(property "Description" ""
			(at 138.43 77.47 0)
			(effects
				(font
					(size 1.27 1.27)
				)
				(hide yes)
			)
		)
		(property "Author" "Antmicro"
			(at 147.32 85.09 0)
			(effects
				(font
					(size 1.27 1.27)
					(thickness 0.15)
				)
				(justify left bottom)
				(hide yes)
			)
		)
		(property "License" "Apache-2.0"
			(at 147.32 87.63 0)
			(effects
				(font
					(size 1.27 1.27)
					(thickness 0.15)
				)
				(justify left bottom)
				(hide yes)
			)
		)
		(pin "1"
		)
		(instances
			(project "gmsl-deserializer"
				(path ""
					(reference "#PWR010")
					(unit 1)
				)
			)
		)
	)
	(symbol
		(lib_id "antmicroTestPoints:TP_0.75mm_SMD")
		(at 45.72 68.58 90)
		(unit 1)
		(exclude_from_sim no)
		(in_bom yes)
		(on_board yes)
		(dnp no)
		(property "Reference" "TP6"
			(at 44.45 63.5 90)
			(effects
				(font
					(size 1.27 1.27)
					(thickness 0.15)
				)
				(justify right)
			)
		)
		(property "Value" "TP_0.75mm_SMD"
			(at 49.53 57.785 0)
			(effects
				(font
					(size 1.27 1.27)
					(thickness 0.15)
				)
				(justify left bottom)
				(hide yes)
			)
		)
		(property "Footprint" "antmicro-footprints:TP_SMD_0.75mm"
			(at 52.07 57.785 0)
			(effects
				(font
					(size 1.27 1.27)
					(thickness 0.15)
				)
				(justify left bottom)
				(hide yes)
			)
		)
		(property "Datasheet" ""
			(at 58.42 50.8 0)
			(effects
				(font
					(size 1.27 1.27)
					(thickness 0.15)
				)
				(justify left bottom)
				(hide yes)
			)
		)
		(property "Description" "SMT test point"
			(at 45.72 68.58 0)
			(effects
				(font
					(size 1.27 1.27)
				)
				(hide yes)
			)
		)
		(property "MPN" ""
			(at 57.15 57.785 0)
			(effects
				(font
					(size 1.27 1.27)
					(thickness 0.15)
				)
				(justify left bottom)
				(hide yes)
			)
		)
		(property "Manufacturer" ""
			(at 52.07 57.785 0)
			(effects
				(font
					(size 1.27 1.27)
					(thickness 0.15)
				)
				(justify left bottom)
				(hide yes)
			)
		)
		(property "Author" "Antmicro"
			(at 54.61 57.785 0)
			(effects
				(font
					(size 1.27 1.27)
					(thickness 0.15)
				)
				(justify left bottom)
				(hide yes)
			)
		)
		(property "License" "Apache-2.0"
			(at 57.15 57.785 0)
			(effects
				(font
					(size 1.27 1.27)
					(thickness 0.15)
				)
				(justify left bottom)
				(hide yes)
			)
		)
		(pin "1"
		)
		(instances
			(project "gmsl-deserializer"
				(path ""
					(reference "TP6")
					(unit 1)
				)
			)
		)
	)
	(symbol
		(lib_id "antmicroTVSDiodes:ESD5B5_0ST1G")
		(at 311.15 207.01 90)
		(unit 1)
		(exclude_from_sim no)
		(in_bom yes)
		(on_board yes)
		(dnp no)
		(property "Reference" "D11"
			(at 312.42 203.2 90)
			(effects
				(font
					(size 1.27 1.27)
					(thickness 0.15)
				)
				(justify right)
			)
		)
		(property "Value" "ESD5B5_0ST1G"
			(at 312.42 205.74 90)
			(effects
				(font
					(size 1.27 1.27)
					(thickness 0.15)
				)
				(justify right)
			)
		)
		(property "Footprint" "antmicro-footprints:SOD-523_NP"
			(at 321.31 181.61 0)
			(effects
				(font
					(size 1.27 1.27)
					(thickness 0.15)
				)
				(justify left bottom)
				(hide yes)
			)
		)
		(property "Datasheet" "https://www.onsemi.com/pdf/datasheet/esd5b5.0st1-d.pdf"
			(at 323.85 181.61 0)
			(effects
				(font
					(size 1.27 1.27)
					(thickness 0.15)
				)
				(justify left bottom)
				(hide yes)
			)
		)
		(property "Description" "Bidirectional TVS, 30 kV,  SOD-523, 5 V, 32 pF"
			(at 311.15 207.01 0)
			(effects
				(font
					(size 1.27 1.27)
				)
				(hide yes)
			)
		)
		(property "Manufacturer" "ON Semiconductor"
			(at 326.39 181.61 0)
			(effects
				(font
					(size 1.27 1.27)
					(thickness 0.15)
				)
				(justify left bottom)
				(hide yes)
			)
		)
		(property "MPN" "ESD5B5.0ST1G"
			(at 328.93 181.61 0)
			(effects
				(font
					(size 1.27 1.27)
					(thickness 0.15)
				)
				(justify left bottom)
				(hide yes)
			)
		)
		(property "Author" "Antmicro"
			(at 331.47 181.61 0)
			(effects
				(font
					(size 1.27 1.27)
					(thickness 0.15)
				)
				(justify left bottom)
				(hide yes)
			)
		)
		(property "License" "Apache-2.0"
			(at 334.01 181.61 0)
			(effects
				(font
					(size 1.27 1.27)
					(thickness 0.15)
				)
				(justify left bottom)
				(hide yes)
			)
		)
		(pin "1"
		)
		(pin "2"
		)
		(instances
			(project "gmsl-deserializer"
				(path ""
					(reference "D11")
					(unit 1)
				)
			)
		)
	)
	(symbol
		(lib_id "antmicroResistors0402:R_100R_0402")
		(at 327.66 177.8 0)
		(unit 1)
		(exclude_from_sim no)
		(in_bom yes)
		(on_board yes)
		(dnp no)
		(property "Reference" "R13"
			(at 328.295 176.53 0)
			(effects
				(font
					(size 1.27 1.27)
					(thickness 0.15)
				)
				(justify right)
			)
		)
		(property "Value" "R_100R_0402"
			(at 347.98 190.5 0)
			(effects
				(font
					(size 1.27 1.27)
					(thickness 0.15)
				)
				(justify left bottom)
				(hide yes)
			)
		)
		(property "Footprint" "antmicro-footprints:R_0402_1005Metric"
			(at 347.98 193.04 0)
			(effects
				(font
					(size 1.27 1.27)
					(thickness 0.15)
				)
				(justify left bottom)
				(hide yes)
			)
		)
		(property "Datasheet" "https://www.bourns.com/docs/product-datasheets/cr.pdf"
			(at 347.98 195.58 0)
			(effects
				(font
					(size 1.27 1.27)
					(thickness 0.15)
				)
				(justify left bottom)
				(hide yes)
			)
		)
		(property "Description" "SMD Chip Resistor, 100 ohm, ± 1%, 62.5 mW, 0402 [1005 Metric], Thick Film, General Purpose"
			(at 327.66 177.8 0)
			(effects
				(font
					(size 1.27 1.27)
				)
				(hide yes)
			)
		)
		(property "MPN" "CR0402-FX-1000GLF"
			(at 347.98 198.12 0)
			(effects
				(font
					(size 1.27 1.27)
					(thickness 0.15)
				)
				(justify left bottom)
				(hide yes)
			)
		)
		(property "Manufacturer" "Bourns"
			(at 347.98 200.66 0)
			(effects
				(font
					(size 1.27 1.27)
					(thickness 0.15)
				)
				(justify left bottom)
				(hide yes)
			)
		)
		(property "License" "Apache-2.0"
			(at 347.98 203.2 0)
			(effects
				(font
					(size 1.27 1.27)
					(thickness 0.15)
				)
				(justify left bottom)
				(hide yes)
			)
		)
		(property "Author" "Antmicro"
			(at 347.98 205.74 0)
			(effects
				(font
					(size 1.27 1.27)
					(thickness 0.15)
				)
				(justify left bottom)
				(hide yes)
			)
		)
		(property "Val" "100R"
			(at 334.645 176.53 0)
			(effects
				(font
					(size 1.27 1.27)
					(thickness 0.15)
				)
			)
		)
		(property "Tolerance" "1%"
			(at 347.98 187.96 0)
			(effects
				(font
					(size 1.27 1.27)
				)
				(justify left bottom)
				(hide yes)
			)
		)
		(pin "1"
		)
		(pin "2"
		)
		(instances
			(project "gmsl-deserializer"
				(path ""
					(reference "R13")
					(unit 1)
				)
			)
		)
	)
	(symbol
		(lib_id "antmicroTVSDiodes:ESD5B5_0ST1G")
		(at 303.53 185.42 90)
		(unit 1)
		(exclude_from_sim no)
		(in_bom yes)
		(on_board yes)
		(dnp no)
		(property "Reference" "D8"
			(at 301.625 181.61 90)
			(effects
				(font
					(size 1.27 1.27)
					(thickness 0.15)
				)
				(justify left)
			)
		)
		(property "Value" "ESD5B5_0ST1G"
			(at 287.02 184.15 90)
			(effects
				(font
					(size 1.27 1.27)
					(thickness 0.15)
				)
				(justify right)
			)
		)
		(property "Footprint" "antmicro-footprints:SOD-523_NP"
			(at 313.69 160.02 0)
			(effects
				(font
					(size 1.27 1.27)
					(thickness 0.15)
				)
				(justify left bottom)
				(hide yes)
			)
		)
		(property "Datasheet" "https://www.onsemi.com/pdf/datasheet/esd5b5.0st1-d.pdf"
			(at 316.23 160.02 0)
			(effects
				(font
					(size 1.27 1.27)
					(thickness 0.15)
				)
				(justify left bottom)
				(hide yes)
			)
		)
		(property "Description" "Bidirectional TVS, 30 kV,  SOD-523, 5 V, 32 pF"
			(at 303.53 185.42 0)
			(effects
				(font
					(size 1.27 1.27)
				)
				(hide yes)
			)
		)
		(property "Manufacturer" "ON Semiconductor"
			(at 318.77 160.02 0)
			(effects
				(font
					(size 1.27 1.27)
					(thickness 0.15)
				)
				(justify left bottom)
				(hide yes)
			)
		)
		(property "MPN" "ESD5B5.0ST1G"
			(at 321.31 160.02 0)
			(effects
				(font
					(size 1.27 1.27)
					(thickness 0.15)
				)
				(justify left bottom)
				(hide yes)
			)
		)
		(property "Author" "Antmicro"
			(at 323.85 160.02 0)
			(effects
				(font
					(size 1.27 1.27)
					(thickness 0.15)
				)
				(justify left bottom)
				(hide yes)
			)
		)
		(property "License" "Apache-2.0"
			(at 326.39 160.02 0)
			(effects
				(font
					(size 1.27 1.27)
					(thickness 0.15)
				)
				(justify left bottom)
				(hide yes)
			)
		)
		(pin "1"
		)
		(pin "2"
		)
		(instances
			(project "gmsl-deserializer"
				(path ""
					(reference "D8")
					(unit 1)
				)
			)
		)
	)
	(symbol
		(lib_id "antmicroLEDIndicationDiscrete:LED_G_0603_LTST-C190GKT")
		(at 266.7 215.9 270)
		(mirror x)
		(unit 1)
		(exclude_from_sim no)
		(in_bom yes)
		(on_board yes)
		(dnp no)
		(property "Reference" "D13"
			(at 270.51 212.09 90)
			(effects
				(font
					(size 1.27 1.27)
					(thickness 0.15)
				)
				(justify left)
			)
		)
		(property "Value" "LED_G_0603_LTST-C190GKT"
			(at 238.125 210.82 90)
			(effects
				(font
					(size 1.27 1.27)
					(thickness 0.15)
				)
				(justify left)
				(hide yes)
			)
		)
		(property "Footprint" "antmicro-footprints:LED_0603_1608Metric_G"
			(at 256.54 193.04 0)
			(effects
				(font
					(size 1.27 1.27)
					(thickness 0.15)
				)
				(justify left bottom)
				(hide yes)
			)
		)
		(property "Datasheet" "https://media.digikey.com/pdf/Data%20Sheets/Lite-On%20PDFs/LTST-C190GKT.pdf"
			(at 254 193.04 0)
			(effects
				(font
					(size 1.27 1.27)
					(thickness 0.15)
				)
				(justify left bottom)
				(hide yes)
			)
		)
		(property "Description" "LED, Green, SMD, 0603, 20 mA, 2.1 V, 569 nm"
			(at 266.7 215.9 0)
			(effects
				(font
					(size 1.27 1.27)
				)
				(hide yes)
			)
		)
		(property "MPN" "LTST-C190GKT"
			(at 270.51 213.36 90)
			(effects
				(font
					(size 1.27 1.27)
					(thickness 0.15)
				)
				(justify left bottom)
			)
		)
		(property "Manufacturer" "Lite-On"
			(at 248.92 193.04 0)
			(effects
				(font
					(size 1.27 1.27)
					(thickness 0.15)
				)
				(justify left bottom)
				(hide yes)
			)
		)
		(property "Author" "Antmicro"
			(at 246.38 193.04 0)
			(effects
				(font
					(size 1.27 1.27)
					(thickness 0.15)
				)
				(justify left bottom)
				(hide yes)
			)
		)
		(property "License" "Apache-2.0"
			(at 243.84 193.04 0)
			(effects
				(font
					(size 1.27 1.27)
					(thickness 0.15)
				)
				(justify left bottom)
				(hide yes)
			)
		)
		(property "VSD_class" "LED"
			(at 241.3 193.04 0)
			(effects
				(font
					(size 1.27 1.27)
				)
				(justify left bottom)
				(hide yes)
			)
		)
		(property "Color" "Green"
			(at 261.62 193.04 0)
			(effects
				(font
					(size 1.27 1.27)
				)
				(justify left bottom)
				(hide yes)
			)
		)
		(pin "1"
		)
		(pin "2"
		)
		(instances
			(project "gmsl-deserializer"
				(path ""
					(reference "D13")
					(unit 1)
				)
			)
		)
	)
	(symbol
		(lib_id "antmicroResistors0402:R_100R_0402")
		(at 107.95 134.62 0)
		(mirror x)
		(unit 1)
		(exclude_from_sim no)
		(in_bom yes)
		(on_board yes)
		(dnp no)
		(property "Reference" "R67"
			(at 108.585 135.89 0)
			(effects
				(font
					(size 1.27 1.27)
					(thickness 0.15)
				)
				(justify right)
			)
		)
		(property "Value" "R_100R_0402"
			(at 128.27 121.92 0)
			(effects
				(font
					(size 1.27 1.27)
					(thickness 0.15)
				)
				(justify left bottom)
				(hide yes)
			)
		)
		(property "Footprint" "antmicro-footprints:R_0402_1005Metric"
			(at 128.27 119.38 0)
			(effects
				(font
					(size 1.27 1.27)
					(thickness 0.15)
				)
				(justify left bottom)
				(hide yes)
			)
		)
		(property "Datasheet" "https://www.bourns.com/docs/product-datasheets/cr.pdf"
			(at 128.27 116.84 0)
			(effects
				(font
					(size 1.27 1.27)
					(thickness 0.15)
				)
				(justify left bottom)
				(hide yes)
			)
		)
		(property "Description" "SMD Chip Resistor, 100 ohm, ± 1%, 62.5 mW, 0402 [1005 Metric], Thick Film, General Purpose"
			(at 107.95 134.62 0)
			(effects
				(font
					(size 1.27 1.27)
				)
				(hide yes)
			)
		)
		(property "MPN" "CR0402-FX-1000GLF"
			(at 128.27 114.3 0)
			(effects
				(font
					(size 1.27 1.27)
					(thickness 0.15)
				)
				(justify left bottom)
				(hide yes)
			)
		)
		(property "Manufacturer" "Bourns"
			(at 128.27 111.76 0)
			(effects
				(font
					(size 1.27 1.27)
					(thickness 0.15)
				)
				(justify left bottom)
				(hide yes)
			)
		)
		(property "License" "Apache-2.0"
			(at 128.27 109.22 0)
			(effects
				(font
					(size 1.27 1.27)
					(thickness 0.15)
				)
				(justify left bottom)
				(hide yes)
			)
		)
		(property "Author" "Antmicro"
			(at 128.27 106.68 0)
			(effects
				(font
					(size 1.27 1.27)
					(thickness 0.15)
				)
				(justify left bottom)
				(hide yes)
			)
		)
		(property "Val" "100R"
			(at 114.935 135.89 0)
			(effects
				(font
					(size 1.27 1.27)
					(thickness 0.15)
				)
			)
		)
		(property "Tolerance" "1%"
			(at 128.27 124.46 0)
			(effects
				(font
					(size 1.27 1.27)
				)
				(justify left bottom)
				(hide yes)
			)
		)
		(pin "1"
		)
		(pin "2"
		)
		(instances
			(project "gmsl-deserializer"
				(path ""
					(reference "R67")
					(unit 1)
				)
			)
		)
	)
	(symbol
		(lib_id "antmicropower:GND")
		(at 66.04 111.76 0)
		(unit 1)
		(exclude_from_sim no)
		(in_bom yes)
		(on_board yes)
		(dnp no)
		(property "Reference" "#PWR017"
			(at 74.93 114.3 0)
			(effects
				(font
					(size 1.27 1.27)
					(thickness 0.15)
				)
				(justify left bottom)
				(hide yes)
			)
		)
		(property "Value" "GND"
			(at 66.04 115.57 0)
			(effects
				(font
					(size 1.27 1.27)
					(thickness 0.15)
				)
			)
		)
		(property "Footprint" ""
			(at 74.93 119.38 0)
			(effects
				(font
					(size 1.27 1.27)
					(thickness 0.15)
				)
				(justify left bottom)
				(hide yes)
			)
		)
		(property "Datasheet" ""
			(at 74.93 124.46 0)
			(effects
				(font
					(size 1.27 1.27)
					(thickness 0.15)
				)
				(justify left bottom)
				(hide yes)
			)
		)
		(property "Description" ""
			(at 66.04 111.76 0)
			(effects
				(font
					(size 1.27 1.27)
				)
				(hide yes)
			)
		)
		(property "Author" "Antmicro"
			(at 74.93 119.38 0)
			(effects
				(font
					(size 1.27 1.27)
					(thickness 0.15)
				)
				(justify left bottom)
				(hide yes)
			)
		)
		(property "License" "Apache-2.0"
			(at 74.93 121.92 0)
			(effects
				(font
					(size 1.27 1.27)
					(thickness 0.15)
				)
				(justify left bottom)
				(hide yes)
			)
		)
		(pin "1"
		)
		(instances
			(project "gmsl-deserializer"
				(path ""
					(reference "#PWR017")
					(unit 1)
				)
			)
		)
	)
	(symbol
		(lib_id "antmicroResistors0402:R_100R_0402")
		(at 107.95 132.08 0)
		(unit 1)
		(exclude_from_sim no)
		(in_bom yes)
		(on_board yes)
		(dnp no)
		(property "Reference" "R66"
			(at 108.585 130.81 0)
			(effects
				(font
					(size 1.27 1.27)
					(thickness 0.15)
				)
				(justify right)
			)
		)
		(property "Value" "R_100R_0402"
			(at 128.27 144.78 0)
			(effects
				(font
					(size 1.27 1.27)
					(thickness 0.15)
				)
				(justify left bottom)
				(hide yes)
			)
		)
		(property "Footprint" "antmicro-footprints:R_0402_1005Metric"
			(at 128.27 147.32 0)
			(effects
				(font
					(size 1.27 1.27)
					(thickness 0.15)
				)
				(justify left bottom)
				(hide yes)
			)
		)
		(property "Datasheet" "https://www.bourns.com/docs/product-datasheets/cr.pdf"
			(at 128.27 149.86 0)
			(effects
				(font
					(size 1.27 1.27)
					(thickness 0.15)
				)
				(justify left bottom)
				(hide yes)
			)
		)
		(property "Description" "SMD Chip Resistor, 100 ohm, ± 1%, 62.5 mW, 0402 [1005 Metric], Thick Film, General Purpose"
			(at 107.95 132.08 0)
			(effects
				(font
					(size 1.27 1.27)
				)
				(hide yes)
			)
		)
		(property "MPN" "CR0402-FX-1000GLF"
			(at 128.27 152.4 0)
			(effects
				(font
					(size 1.27 1.27)
					(thickness 0.15)
				)
				(justify left bottom)
				(hide yes)
			)
		)
		(property "Manufacturer" "Bourns"
			(at 128.27 154.94 0)
			(effects
				(font
					(size 1.27 1.27)
					(thickness 0.15)
				)
				(justify left bottom)
				(hide yes)
			)
		)
		(property "License" "Apache-2.0"
			(at 128.27 157.48 0)
			(effects
				(font
					(size 1.27 1.27)
					(thickness 0.15)
				)
				(justify left bottom)
				(hide yes)
			)
		)
		(property "Author" "Antmicro"
			(at 128.27 160.02 0)
			(effects
				(font
					(size 1.27 1.27)
					(thickness 0.15)
				)
				(justify left bottom)
				(hide yes)
			)
		)
		(property "Val" "100R"
			(at 114.935 130.81 0)
			(effects
				(font
					(size 1.27 1.27)
					(thickness 0.15)
				)
			)
		)
		(property "Tolerance" "1%"
			(at 128.27 142.24 0)
			(effects
				(font
					(size 1.27 1.27)
				)
				(justify left bottom)
				(hide yes)
			)
		)
		(pin "1"
		)
		(pin "2"
		)
		(instances
			(project "gmsl-deserializer"
				(path ""
					(reference "R66")
					(unit 1)
				)
			)
		)
	)
	(symbol
		(lib_id "antmicroLEDIndicationDiscrete:LED_G_0603_LTST-C190GKT")
		(at 41.91 236.22 270)
		(mirror x)
		(unit 1)
		(exclude_from_sim no)
		(in_bom yes)
		(on_board yes)
		(dnp no)
		(property "Reference" "D14"
			(at 45.72 233.68 90)
			(effects
				(font
					(size 1.27 1.27)
					(thickness 0.15)
				)
				(justify left)
			)
		)
		(property "Value" "LED_G_0603_LTST-C190GKT"
			(at 13.335 231.14 90)
			(effects
				(font
					(size 1.27 1.27)
					(thickness 0.15)
				)
				(justify left)
				(hide yes)
			)
		)
		(property "Footprint" "antmicro-footprints:LED_0603_1608Metric_G"
			(at 31.75 213.36 0)
			(effects
				(font
					(size 1.27 1.27)
					(thickness 0.15)
				)
				(justify left bottom)
				(hide yes)
			)
		)
		(property "Datasheet" "https://media.digikey.com/pdf/Data%20Sheets/Lite-On%20PDFs/LTST-C190GKT.pdf"
			(at 29.21 213.36 0)
			(effects
				(font
					(size 1.27 1.27)
					(thickness 0.15)
				)
				(justify left bottom)
				(hide yes)
			)
		)
		(property "Description" "LED, Green, SMD, 0603, 20 mA, 2.1 V, 569 nm"
			(at 41.91 236.22 0)
			(effects
				(font
					(size 1.27 1.27)
				)
				(hide yes)
			)
		)
		(property "MPN" "LTST-C190GKT"
			(at 45.72 234.95 90)
			(effects
				(font
					(size 1.27 1.27)
					(thickness 0.15)
				)
				(justify left bottom)
			)
		)
		(property "Manufacturer" "Lite-On"
			(at 24.13 213.36 0)
			(effects
				(font
					(size 1.27 1.27)
					(thickness 0.15)
				)
				(justify left bottom)
				(hide yes)
			)
		)
		(property "Author" "Antmicro"
			(at 21.59 213.36 0)
			(effects
				(font
					(size 1.27 1.27)
					(thickness 0.15)
				)
				(justify left bottom)
				(hide yes)
			)
		)
		(property "License" "Apache-2.0"
			(at 19.05 213.36 0)
			(effects
				(font
					(size 1.27 1.27)
					(thickness 0.15)
				)
				(justify left bottom)
				(hide yes)
			)
		)
		(property "VSD_class" "LED"
			(at 16.51 213.36 0)
			(effects
				(font
					(size 1.27 1.27)
				)
				(justify left bottom)
				(hide yes)
			)
		)
		(property "Color" "Green"
			(at 36.83 213.36 0)
			(effects
				(font
					(size 1.27 1.27)
				)
				(justify left bottom)
				(hide yes)
			)
		)
		(pin "1"
		)
		(pin "2"
		)
		(instances
			(project "gmsl-deserializer"
				(path ""
					(reference "D14")
					(unit 1)
				)
			)
		)
	)
	(symbol
		(lib_id "antmicropower:GND")
		(at 173.99 80.01 0)
		(unit 1)
		(exclude_from_sim no)
		(in_bom yes)
		(on_board yes)
		(dnp no)
		(property "Reference" "#PWR013"
			(at 182.88 82.55 0)
			(effects
				(font
					(size 1.27 1.27)
					(thickness 0.15)
				)
				(justify left bottom)
				(hide yes)
			)
		)
		(property "Value" "GND"
			(at 173.99 83.82 0)
			(effects
				(font
					(size 1.27 1.27)
					(thickness 0.15)
				)
			)
		)
		(property "Footprint" ""
			(at 182.88 87.63 0)
			(effects
				(font
					(size 1.27 1.27)
					(thickness 0.15)
				)
				(justify left bottom)
				(hide yes)
			)
		)
		(property "Datasheet" ""
			(at 182.88 92.71 0)
			(effects
				(font
					(size 1.27 1.27)
					(thickness 0.15)
				)
				(justify left bottom)
				(hide yes)
			)
		)
		(property "Description" ""
			(at 173.99 80.01 0)
			(effects
				(font
					(size 1.27 1.27)
				)
				(hide yes)
			)
		)
		(property "Author" "Antmicro"
			(at 182.88 87.63 0)
			(effects
				(font
					(size 1.27 1.27)
					(thickness 0.15)
				)
				(justify left bottom)
				(hide yes)
			)
		)
		(property "License" "Apache-2.0"
			(at 182.88 90.17 0)
			(effects
				(font
					(size 1.27 1.27)
					(thickness 0.15)
				)
				(justify left bottom)
				(hide yes)
			)
		)
		(pin "1"
		)
		(instances
			(project "gmsl-deserializer"
				(path ""
					(reference "#PWR013")
					(unit 1)
				)
			)
		)
	)
	(symbol
		(lib_id "antmicroTVSDiodes:ESD5B5_0ST1G")
		(at 284.48 170.18 90)
		(unit 1)
		(exclude_from_sim no)
		(in_bom yes)
		(on_board yes)
		(dnp no)
		(property "Reference" "D7"
			(at 285.75 166.37 90)
			(effects
				(font
					(size 1.27 1.27)
					(thickness 0.15)
				)
				(justify right)
			)
		)
		(property "Value" "ESD5B5_0ST1G"
			(at 285.75 168.91 90)
			(effects
				(font
					(size 1.27 1.27)
					(thickness 0.15)
				)
				(justify right)
			)
		)
		(property "Footprint" "antmicro-footprints:SOD-523_NP"
			(at 294.64 144.78 0)
			(effects
				(font
					(size 1.27 1.27)
					(thickness 0.15)
				)
				(justify left bottom)
				(hide yes)
			)
		)
		(property "Datasheet" "https://www.onsemi.com/pdf/datasheet/esd5b5.0st1-d.pdf"
			(at 297.18 144.78 0)
			(effects
				(font
					(size 1.27 1.27)
					(thickness 0.15)
				)
				(justify left bottom)
				(hide yes)
			)
		)
		(property "Description" "Bidirectional TVS, 30 kV,  SOD-523, 5 V, 32 pF"
			(at 284.48 170.18 0)
			(effects
				(font
					(size 1.27 1.27)
				)
				(hide yes)
			)
		)
		(property "Manufacturer" "ON Semiconductor"
			(at 299.72 144.78 0)
			(effects
				(font
					(size 1.27 1.27)
					(thickness 0.15)
				)
				(justify left bottom)
				(hide yes)
			)
		)
		(property "MPN" "ESD5B5.0ST1G"
			(at 302.26 144.78 0)
			(effects
				(font
					(size 1.27 1.27)
					(thickness 0.15)
				)
				(justify left bottom)
				(hide yes)
			)
		)
		(property "Author" "Antmicro"
			(at 304.8 144.78 0)
			(effects
				(font
					(size 1.27 1.27)
					(thickness 0.15)
				)
				(justify left bottom)
				(hide yes)
			)
		)
		(property "License" "Apache-2.0"
			(at 307.34 144.78 0)
			(effects
				(font
					(size 1.27 1.27)
					(thickness 0.15)
				)
				(justify left bottom)
				(hide yes)
			)
		)
		(pin "1"
		)
		(pin "2"
		)
		(instances
			(project "gmsl-deserializer"
				(path ""
					(reference "D7")
					(unit 1)
				)
			)
		)
	)
	(symbol
		(lib_id "antmicropower:GND")
		(at 41.91 255.27 0)
		(unit 1)
		(exclude_from_sim no)
		(in_bom yes)
		(on_board yes)
		(dnp no)
		(property "Reference" "#PWR0122"
			(at 50.8 257.81 0)
			(effects
				(font
					(size 1.27 1.27)
					(thickness 0.15)
				)
				(justify left bottom)
				(hide yes)
			)
		)
		(property "Value" "GND"
			(at 41.91 259.08 0)
			(effects
				(font
					(size 1.27 1.27)
					(thickness 0.15)
				)
			)
		)
		(property "Footprint" ""
			(at 50.8 262.89 0)
			(effects
				(font
					(size 1.27 1.27)
					(thickness 0.15)
				)
				(justify left bottom)
				(hide yes)
			)
		)
		(property "Datasheet" ""
			(at 50.8 267.97 0)
			(effects
				(font
					(size 1.27 1.27)
					(thickness 0.15)
				)
				(justify left bottom)
				(hide yes)
			)
		)
		(property "Description" ""
			(at 41.91 255.27 0)
			(effects
				(font
					(size 1.27 1.27)
				)
				(hide yes)
			)
		)
		(property "Author" "Antmicro"
			(at 50.8 262.89 0)
			(effects
				(font
					(size 1.27 1.27)
					(thickness 0.15)
				)
				(justify left bottom)
				(hide yes)
			)
		)
		(property "License" "Apache-2.0"
			(at 50.8 265.43 0)
			(effects
				(font
					(size 1.27 1.27)
					(thickness 0.15)
				)
				(justify left bottom)
				(hide yes)
			)
		)
		(pin "1"
		)
		(instances
			(project "gmsl-deserializer"
				(path ""
					(reference "#PWR0122")
					(unit 1)
				)
			)
		)
	)
	(symbol
		(lib_id "antmicroLEDIndicationDiscrete:LED_G_0603_LTST-C190GKT")
		(at 259.08 215.9 270)
		(mirror x)
		(unit 1)
		(exclude_from_sim no)
		(in_bom yes)
		(on_board yes)
		(dnp no)
		(property "Reference" "D12"
			(at 256.54 212.09 90)
			(effects
				(font
					(size 1.27 1.27)
					(thickness 0.15)
				)
				(justify right)
			)
		)
		(property "Value" "LED_G_0603_LTST-C190GKT"
			(at 230.505 210.82 90)
			(effects
				(font
					(size 1.27 1.27)
					(thickness 0.15)
				)
				(justify left)
				(hide yes)
			)
		)
		(property "Footprint" "antmicro-footprints:LED_0603_1608Metric_G"
			(at 248.92 193.04 0)
			(effects
				(font
					(size 1.27 1.27)
					(thickness 0.15)
				)
				(justify left bottom)
				(hide yes)
			)
		)
		(property "Datasheet" "https://media.digikey.com/pdf/Data%20Sheets/Lite-On%20PDFs/LTST-C190GKT.pdf"
			(at 246.38 193.04 0)
			(effects
				(font
					(size 1.27 1.27)
					(thickness 0.15)
				)
				(justify left bottom)
				(hide yes)
			)
		)
		(property "Description" "LED, Green, SMD, 0603, 20 mA, 2.1 V, 569 nm"
			(at 259.08 215.9 0)
			(effects
				(font
					(size 1.27 1.27)
				)
				(hide yes)
			)
		)
		(property "MPN" "LTST-C190GKT"
			(at 256.54 214.63 90)
			(effects
				(font
					(size 1.27 1.27)
					(thickness 0.15)
				)
				(justify right top)
			)
		)
		(property "Manufacturer" "Lite-On"
			(at 241.3 193.04 0)
			(effects
				(font
					(size 1.27 1.27)
					(thickness 0.15)
				)
				(justify left bottom)
				(hide yes)
			)
		)
		(property "Author" "Antmicro"
			(at 238.76 193.04 0)
			(effects
				(font
					(size 1.27 1.27)
					(thickness 0.15)
				)
				(justify left bottom)
				(hide yes)
			)
		)
		(property "License" "Apache-2.0"
			(at 236.22 193.04 0)
			(effects
				(font
					(size 1.27 1.27)
					(thickness 0.15)
				)
				(justify left bottom)
				(hide yes)
			)
		)
		(property "VSD_class" "LED"
			(at 233.68 193.04 0)
			(effects
				(font
					(size 1.27 1.27)
				)
				(justify left bottom)
				(hide yes)
			)
		)
		(property "Color" "Green"
			(at 245.11 209.55 90)
			(effects
				(font
					(size 1.27 1.27)
				)
				(justify left bottom)
				(hide yes)
			)
		)
		(pin "1"
		)
		(pin "2"
		)
		(instances
			(project "gmsl-deserializer"
				(path ""
					(reference "D12")
					(unit 1)
				)
			)
		)
	)
)
